# Altium SchDoc records: USER_IO.SchDoc
|HEADER=Protel for Windows - Schematic Capture Binary File Version 5.0|Weight=1389|MinorVersion=2
|RECORD=31|FontIdCount=8|Size1=10|FontName1=Times New Roman|Size2=12|FontName2=Arial|Size3=14|FontName3=Arial|Size4=24|FontName4=Times New Roman|Size5=10|Underline5=T|FontName5=Times New Roman|Size6=8|FontName6=Arial|Size7=10|FontName7=Arial|Size8=12|Underline8=T|FontName8=Arial|UseMBCS=T|IsBOC=T|HotSpotGridOn=T|HotSpotGridSize=1|SheetStyle=12|SystemFont=7|BorderOn=T|SheetNumberSpaceSize=12|AreaColor=16317695|SnapGridOn=T|SnapGridSize=1|VisibleGridOn=T|VisibleGridSize=10|CustomX=2338|CustomX_Frac=58268|CustomY=1653|CustomY_Frac=54331|CustomXZones=8|CustomYZones=6|CustomMarginWidth=19|CustomMarginWidth_Frac=80000|ShowTemplateGraphics=T|TemplateFileName=C:\Users\<user>\Documents\Altium\AD20\Templates\Timecard.SchDot|Display_Unit=0
|RECORD=39|IsNotAccesible=T|OwnerPartId=-1|FileName=C:\Users\<user>\Documents\Altium\AD20\Templates\Timecard.SchDot
|RECORD=4|OwnerIndex=1|OwnerPartId=-1|Location.X=1594|Location.Y=39|Color=8388608|FontID=8|Text=timingcard.com|URL=http://timingcard.com
|RECORD=6|OwnerIndex=1|IndexInSheet=1|OwnerPartId=-1|LocationCount=2|X1=1680|Y1=35|X2=1576|Y2=35
|RECORD=4|OwnerIndex=1|IndexInSheet=2|OwnerPartId=-1|Location.X=1614|Location.X_Frac=42446|Location.Y=19|Location.Y_Frac=96838|FontID=2|Text==SheetNumber
|RECORD=4|OwnerIndex=1|IndexInSheet=3|OwnerPartId=-1|Location.X=1581|Location.X_Frac=42446|Location.Y=29|Location.Y_Frac=96838|Justification=3|FontID=6|Text=SHEET
|RECORD=4|OwnerIndex=1|IndexInSheet=4|OwnerPartId=-1|Location.X=1639|Location.X_Frac=42446|Location.Y=29|Location.Y_Frac=96838|Justification=3|FontID=6|Text=OF
|RECORD=6|OwnerIndex=1|IndexInSheet=5|OwnerPartId=-1|LineWidth=1|LocationCount=2|X1=1679|X1_Frac=42446|Y1=105|Y1_Frac=96838|X2=1576|Y2=106
|RECORD=4|OwnerIndex=1|IndexInSheet=6|OwnerPartId=-1|Location.X=1658|Location.Y=20|FontID=2|Text==SheetTotal
|RECORD=30|OwnerIndex=1|IndexInSheet=7|OwnerPartId=-1|Location.X=1578|Location.Y=53|Corner.X=1673|Corner.X_Frac=88801|Corner.Y=103|KeepAspect=T|FileName=C:\Users\<user>\Desktop\Timecard Logo\TIMECARD.jpg
|RECORD=6|OwnerIndex=1|IndexInSheet=8|OwnerPartId=-1|LineWidth=1|LocationCount=2|X1=1576|X1_Frac=3162|Y1=105|Y1_Frac=42446|X2=1576|Y2=20
|RECORD=6|OwnerIndex=1|IndexInSheet=9|OwnerPartId=-1|LocationCount=2|X1=1680|Y1=51|X2=1576|Y2=51
|RECORD=41|IndexInSheet=1|OwnerPartId=-1|Color=8388608|FontID=1|IsHidden=T|Text=*|Name=CurrentTime|ReadOnlyState=1
|RECORD=41|IndexInSheet=2|OwnerPartId=-1|Color=8388608|FontID=1|IsHidden=T|Text=*|Name=CurrentDate|ReadOnlyState=1
|RECORD=41|IndexInSheet=3|OwnerPartId=-1|Color=8388608|FontID=1|IsHidden=T|Text=*|Name=Time|ReadOnlyState=1
|RECORD=41|IndexInSheet=4|OwnerPartId=-1|Color=8388608|FontID=1|IsHidden=T|Text=*|Name=Date|ReadOnlyState=1
|RECORD=41|IndexInSheet=5|OwnerPartId=-1|Color=8388608|FontID=1|IsHidden=T|Text=*|Name=DocumentFullPathAndName|ReadOnlyState=1
|RECORD=41|IndexInSheet=6|OwnerPartId=-1|Color=8388608|FontID=1|IsHidden=T|Text=*|Name=DocumentName|ReadOnlyState=1
|RECORD=41|IndexInSheet=7|OwnerPartId=-1|Color=8388608|FontID=1|IsHidden=T|Text=*|Name=ModifiedDate|ReadOnlyState=1
|RECORD=41|IndexInSheet=8|OwnerPartId=-1|Color=8388608|FontID=1|IsHidden=T|Text=*|Name=ApprovedBy|ReadOnlyState=1
|RECORD=41|IndexInSheet=9|OwnerPartId=-1|Color=8388608|FontID=1|IsHidden=T|Text=*|Name=CheckedBy|ReadOnlyState=1
|RECORD=41|IndexInSheet=10|OwnerPartId=-1|Color=8388608|FontID=1|IsHidden=T|Text=*|Name=Author|ReadOnlyState=1
|RECORD=41|IndexInSheet=11|OwnerPartId=-1|Color=8388608|FontID=1|IsHidden=T|Text=*|Name=CompanyName|ReadOnlyState=1
|RECORD=41|IndexInSheet=12|OwnerPartId=-1|Color=8388608|FontID=1|IsHidden=T|Text=*|Name=DrawnBy|ReadOnlyState=1
|RECORD=41|IndexInSheet=13|OwnerPartId=-1|Color=8388608|FontID=1|IsHidden=T|Text=*|Name=Engineer|ReadOnlyState=1
|RECORD=41|IndexInSheet=14|OwnerPartId=-1|Color=8388608|FontID=1|IsHidden=T|Text=*|Name=Organization|ReadOnlyState=1
|RECORD=41|IndexInSheet=15|OwnerPartId=-1|Color=8388608|FontID=1|IsHidden=T|Text=*|Name=Address1|ReadOnlyState=1
|RECORD=41|IndexInSheet=16|OwnerPartId=-1|Color=8388608|FontID=1|IsHidden=T|Text=*|Name=Address2|ReadOnlyState=1
|RECORD=41|IndexInSheet=17|OwnerPartId=-1|Color=8388608|FontID=1|IsHidden=T|Text=*|Name=Address3|ReadOnlyState=1
|RECORD=41|IndexInSheet=18|OwnerPartId=-1|Color=8388608|FontID=1|IsHidden=T|Text=*|Name=Address4|ReadOnlyState=1
|RECORD=41|IndexInSheet=19|OwnerPartId=-1|Color=8388608|FontID=1|IsHidden=T|Text=*|Name=Title|ReadOnlyState=1
|RECORD=41|IndexInSheet=20|OwnerPartId=-1|Color=8388608|FontID=1|IsHidden=T|Text=*|Name=DocumentNumber|ReadOnlyState=1
|RECORD=41|IndexInSheet=21|OwnerPartId=-1|Color=8388608|FontID=1|IsHidden=T|Text=*|Name=Revision|ReadOnlyState=1
|RECORD=41|IndexInSheet=22|OwnerPartId=-1|Color=8388608|FontID=1|IsHidden=T|Text=1|Name=SheetNumber|ReadOnlyState=1
|RECORD=41|IndexInSheet=23|OwnerPartId=-1|Color=8388608|FontID=1|IsHidden=T|Text=7|Name=SheetTotal|ReadOnlyState=1
|RECORD=41|IndexInSheet=24|OwnerPartId=-1|Color=8388608|FontID=1|IsHidden=T|Text=*|Name=Rule|ReadOnlyState=1
|RECORD=41|IndexInSheet=25|OwnerPartId=-1|Color=8388608|FontID=1|IsHidden=T|Text=*|Name=ImagePath|ReadOnlyState=1
|RECORD=41|IndexInSheet=26|OwnerPartId=-1|Color=8388608|FontID=1|IsHidden=T|Text=*|Name=ProjectName|ReadOnlyState=1
|RECORD=41|IndexInSheet=27|OwnerPartId=-1|Color=8388608|FontID=1|IsHidden=T|Text=*|Name=Application_BuildNumber|ReadOnlyState=1
|RECORD=17|IndexInSheet=28|OwnerPartId=-1|Style=4|ShowNetName=T|Location.X=710|Location.Y=410|Orientation=3|Color=128|FontID=1|Text=GND
|RECORD=17|IndexInSheet=29|OwnerPartId=-1|Style=4|ShowNetName=T|Location.X=400|Location.Y=410|Orientation=3|Color=128|FontID=1|Text=GND
|RECORD=17|IndexInSheet=30|OwnerPartId=-1|ShowNetName=T|Location.X=580|Location.Y=480|Orientation=1|Color=128|FontID=1|Text=+3.3V
|RECORD=17|IndexInSheet=31|OwnerPartId=-1|ShowNetName=T|Location.X=270|Location.Y=480|Orientation=1|Color=128|FontID=1|Text=+3.3V
|RECORD=17|IndexInSheet=32|OwnerPartId=-1|ShowNetName=T|Location.X=640|Location.Y=750|Orientation=1|Color=128|FontID=1|Text=+3.3V
|RECORD=17|IndexInSheet=33|OwnerPartId=-1|ShowNetName=T|Location.X=540|Location.Y=750|Orientation=1|Color=128|FontID=1|Text=+3.3V
|RECORD=17|IndexInSheet=34|OwnerPartId=-1|ShowNetName=T|Location.X=440|Location.Y=750|Orientation=1|Color=128|FontID=1|Text=+3.3V
|RECORD=17|IndexInSheet=35|OwnerPartId=-1|ShowNetName=T|Location.X=340|Location.Y=750|Orientation=1|Color=128|FontID=1|Text=+3.3V
|RECORD=17|IndexInSheet=36|OwnerPartId=-1|ShowNetName=T|Location.X=520|Location.Y=420|Orientation=2|Color=255|FontID=1|Text=KEY2|IsCrossSheetConnector=T
|RECORD=17|IndexInSheet=37|OwnerPartId=-1|ShowNetName=T|Location.X=210|Location.Y=420|Orientation=2|Color=255|FontID=1|Text=KEY1|IsCrossSheetConnector=T
|RECORD=17|IndexInSheet=38|OwnerPartId=-1|ShowNetName=T|Location.X=330|Location.Y=620|Orientation=2|Color=255|FontID=1|Text=LED1|IsCrossSheetConnector=T
|RECORD=17|IndexInSheet=39|OwnerPartId=-1|ShowNetName=T|Location.X=430|Location.Y=620|Orientation=2|Color=255|FontID=1|Text=LED2|IsCrossSheetConnector=T
|RECORD=17|IndexInSheet=40|OwnerPartId=-1|ShowNetName=T|Location.X=530|Location.Y=620|Orientation=2|Color=255|FontID=1|Text=LED3|IsCrossSheetConnector=T
|RECORD=17|IndexInSheet=41|OwnerPartId=-1|ShowNetName=T|Location.X=630|Location.Y=620|Orientation=2|Color=255|FontID=1|Text=LED4|IsCrossSheetConnector=T
|RECORD=1|LibReference=SMTLED_RED_0603_SML|ComponentDescription=LED, RED, SML-LX0603, 635NM, 2V, 20MA, 0603|PartCount=2|DisplayModeCount=1|IndexInSheet=42|OwnerPartId=-1|Location.X=640|Location.Y=750|Orientation=3|CurrentPartId=1|LibraryPath=*|SourceLibraryName=Passives.IntLib|TargetFileName=*|AreaColor=11599871|Color=128|PartIDLocked=F|DesignItemId=SMTLED_RED_0603_SML|AllPinCount=2
|RECORD=41|OwnerIndex=53|OwnerPartId=-1|Location.X=627|Location.X_Frac=50000|Location.Y=752|Color=8388608|FontID=2|IsHidden=T|Text=SML-LX0603IW-TR|Name=MFG PART NUM
|RECORD=41|OwnerIndex=53|IndexInSheet=1|OwnerPartId=-1|Location.X=627|Location.X_Frac=50000|Location.Y=752|Color=8388608|FontID=2|IsHidden=T|Text=9/4/2013|Name=MODIFY DATE
|RECORD=41|OwnerIndex=53|IndexInSheet=2|OwnerPartId=-1|Location.X=627|Location.X_Frac=50000|Location.Y=752|Color=8388608|FontID=2|IsHidden=T|Text=LUMEX|Name=MFG NAME
|RECORD=41|OwnerIndex=53|IndexInSheet=3|OwnerPartId=-1|Location.X=627|Location.X_Frac=50000|Location.Y=752|Color=8388608|FontID=2|IsHidden=T|Text=LED|Name=CATEGORY
|RECORD=41|OwnerIndex=53|IndexInSheet=4|OwnerPartId=-1|Location.X=627|Location.X_Frac=50000|Location.Y=752|Color=8388608|FontID=2|IsHidden=T|Name=Date
|RECORD=41|OwnerIndex=53|IndexInSheet=5|OwnerPartId=-1|Location.X=627|Location.X_Frac=50000|Location.Y=752|Color=8388608|FontID=2|IsHidden=T|Text=85C|Name=MAXTEMP
|RECORD=41|OwnerIndex=53|IndexInSheet=6|OwnerPartId=-1|Location.X=627|Location.X_Frac=50000|Location.Y=752|Color=8388608|FontID=2|IsHidden=T|Text=-25C|Name=MINTEMP
|RECORD=41|OwnerIndex=53|IndexInSheet=7|OwnerPartId=-1|Location.X=627|Location.X_Frac=50000|Location.Y=752|Color=8388608|FontID=2|IsHidden=T|Text=SML-LX0603|Name=OTHER
|RECORD=41|OwnerIndex=53|IndexInSheet=8|OwnerPartId=-1|Location.X=627|Location.X_Frac=50000|Location.Y=752|Color=8388608|FontID=2|IsHidden=T|Text=635NM|Name=P1
|RECORD=41|OwnerIndex=53|IndexInSheet=9|OwnerPartId=-1|Location.X=627|Location.X_Frac=50000|Location.Y=752|Color=8388608|FontID=2|IsHidden=T|Text=2V|Name=P2
|RECORD=41|OwnerIndex=53|IndexInSheet=10|OwnerPartId=-1|Location.X=627|Location.X_Frac=50000|Location.Y=752|Color=8388608|FontID=2|IsHidden=T|Text=20MA|Name=P3
|RECORD=41|OwnerIndex=53|IndexInSheet=11|OwnerPartId=-1|Location.X=627|Location.X_Frac=50000|Location.Y=752|Color=8388608|FontID=2|IsHidden=T|Name=SUB
|RECORD=41|OwnerIndex=53|IndexInSheet=12|OwnerPartId=-1|Location.X=627|Location.X_Frac=50000|Location.Y=752|Color=8388608|FontID=2|IsHidden=T|Text=0603|Name=SIZE
|RECORD=41|OwnerIndex=53|IndexInSheet=13|OwnerPartId=-1|Location.X=627|Location.X_Frac=50000|Location.Y=752|Color=8388608|FontID=1|IsHidden=T|Text=*|Name=SHEETPART
|RECORD=41|OwnerIndex=53|IndexInSheet=14|OwnerPartId=-1|Location.X=627|Location.X_Frac=50000|Location.Y=752|Color=8388608|FontID=1|IsHidden=T|Text=LED, RED, SML-LX0603, 635NM, 2V, 20MA, 0603|Name=DESC
|RECORD=41|OwnerIndex=53|IndexInSheet=15|OwnerPartId=-1|Location.X=627|Location.X_Frac=50000|Location.Y=752|Color=8388608|FontID=1|IsHidden=T|Text=Digi-Key|Name=Supplier 1|ReadOnlyState=3
|RECORD=41|OwnerIndex=53|IndexInSheet=16|OwnerPartId=-1|Location.X=627|Location.X_Frac=50000|Location.Y=752|Color=8388608|FontID=1|IsHidden=T|Text=67-1548-1-ND|Name=Supplier Part Number 1|ReadOnlyState=3
|RECORD=41|OwnerIndex=53|IndexInSheet=17|OwnerPartId=-1|Location.X=660|Location.Y=706|Location.Y_Frac=50000|Color=8388608|FontID=2|Text=RED|Name=VALUE
|RECORD=2|OwnerIndex=53|OwnerPartId=1|FormalType=1|Electrical=4|PinConglomerate=33|PinLength=20|Location.X=640|Location.Y=730|Name=A|Designator=2|PinPropagationDelay=0.000000E+000
|RECORD=2|OwnerIndex=53|OwnerPartId=1|FormalType=1|Electrical=4|PinConglomerate=35|PinLength=20|Location.X=640|Location.Y=710|Name=K|Designator=1|PinPropagationDelay=0.000000E+000
|RECORD=12|OwnerIndex=53|IsNotAccesible=T|IndexInSheet=20|OwnerPartId=1|Location.X=640|Location.Y=720|Radius=12|Radius_Frac=50000|LineWidth=1|EndAngle=360.000|Color=16711680
|RECORD=13|OwnerIndex=53|IsNotAccesible=T|IndexInSheet=21|OwnerPartId=1|Location.X=648|Location.Y=714|Corner.X=633|Corner.Y=714|LineWidth=1|Color=16711680
|RECORD=13|OwnerIndex=53|IsNotAccesible=T|IndexInSheet=22|OwnerPartId=1|Location.X=655|Location.Y=701|Corner.X=648|Corner.X_Frac=70000|Corner.Y=707|Corner.Y_Frac=20000|LineWidth=1|Color=16711680
|RECORD=13|OwnerIndex=53|IsNotAccesible=T|IndexInSheet=23|OwnerPartId=1|Location.X=659|Location.Y=705|Corner.X=652|Corner.X_Frac=80000|Corner.Y=711|Corner.Y_Frac=30000|LineWidth=1|Color=16711680
|RECORD=13|OwnerIndex=53|IsNotAccesible=T|IndexInSheet=24|OwnerPartId=1|Location.X=640|Location.Y=710|Corner.X=640|Corner.Y=713|Corner.Y_Frac=80000|LineWidth=1|Color=16711680
|RECORD=13|OwnerIndex=53|IsNotAccesible=T|IndexInSheet=25|OwnerPartId=1|Location.X=640|Location.Y=726|Corner.X=640|Corner.Y=729|Corner.Y_Frac=70000|LineWidth=1|Color=16711680
|RECORD=7|OwnerIndex=53|IsNotAccesible=T|IndexInSheet=26|OwnerPartId=1|LineWidth=1|Color=16711680|AreaColor=16711680|IsSolid=T|LocationCount=3|X1=654|Y1=704|X2=652|Y2=702|X3=655|Y3=701
|RECORD=7|OwnerIndex=53|IsNotAccesible=T|IndexInSheet=27|OwnerPartId=1|LineWidth=1|Color=16711680|AreaColor=16711680|IsSolid=T|LocationCount=3|X1=658|Y1=708|X2=656|Y2=706|X3=659|Y3=705
|RECORD=7|OwnerIndex=53|IsNotAccesible=T|IndexInSheet=28|OwnerPartId=1|LineWidth=1|Color=16711680|AreaColor=16777215|IsSolid=T|LocationCount=3|X1=640|Y1=714|X2=648|Y2=726|X3=632|Y3=726
|RECORD=41|OwnerIndex=53|IndexInSheet=29|OwnerPartId=-1|Location.X=627|Location.X_Frac=50000|Location.Y=752|Color=8388608|FontID=1|IsHidden=T|Text=<VALENTIUM>|Name=VALENTIUM PART NUM
|RECORD=34|OwnerIndex=53|IndexInSheet=-1|OwnerPartId=-1|Location.X=660|Location.Y=718|Location.Y_Frac=50000|Color=8388608|FontID=3|Text=D14|Name=Designator|ReadOnlyState=1
|RECORD=41|OwnerIndex=53|IndexInSheet=-1|OwnerPartId=-1|Location.X=627|Location.X_Frac=50000|Location.Y=752|Color=8388608|FontID=2|IsHidden=T|Text==VALUE|Name=Comment|ReadOnlyState=1
|RECORD=44|OwnerIndex=53
|RECORD=45|OwnerIndex=88|IndexInSheet=-1|Description=Molded Diode, 0603, 2-Leads, Body 1.60x0.80mm, IPC Medium Density|UseComponentLibrary=T|ModelName=DIOM1608X06N|ModelType=PCBLIB|DatafileCount=1|ModelDatafileEntity0=DIOM1608X06N|ModelDatafileKind0=PCBLib|IsCurrent=T|DatalinksLocked=T|DatabaseDatalinksLocked=T|IntegratedModel=T|DatabaseModel=T
|RECORD=46|OwnerIndex=89
|RECORD=48|OwnerIndex=89
|RECORD=1|LibReference=SMTLED_RED_0603_SML|ComponentDescription=LED, RED, SML-LX0603, 635NM, 2V, 20MA, 0603|PartCount=2|DisplayModeCount=1|IndexInSheet=43|OwnerPartId=-1|Location.X=540|Location.Y=750|Orientation=3|CurrentPartId=1|LibraryPath=*|SourceLibraryName=Passives.IntLib|TargetFileName=*|AreaColor=11599871|Color=128|PartIDLocked=F|DesignItemId=SMTLED_RED_0603_SML|AllPinCount=2
|RECORD=41|OwnerIndex=92|OwnerPartId=-1|Location.X=527|Location.X_Frac=50000|Location.Y=752|Color=8388608|FontID=2|IsHidden=T|Text=SML-LX0603IW-TR|Name=MFG PART NUM
|RECORD=41|OwnerIndex=92|IndexInSheet=1|OwnerPartId=-1|Location.X=527|Location.X_Frac=50000|Location.Y=752|Color=8388608|FontID=2|IsHidden=T|Text=9/4/2013|Name=MODIFY DATE
|RECORD=41|OwnerIndex=92|IndexInSheet=2|OwnerPartId=-1|Location.X=527|Location.X_Frac=50000|Location.Y=752|Color=8388608|FontID=2|IsHidden=T|Text=LUMEX|Name=MFG NAME
|RECORD=41|OwnerIndex=92|IndexInSheet=3|OwnerPartId=-1|Location.X=527|Location.X_Frac=50000|Location.Y=752|Color=8388608|FontID=2|IsHidden=T|Text=LED|Name=CATEGORY
|RECORD=41|OwnerIndex=92|IndexInSheet=4|OwnerPartId=-1|Location.X=527|Location.X_Frac=50000|Location.Y=752|Color=8388608|FontID=2|IsHidden=T|Name=Date
|RECORD=41|OwnerIndex=92|IndexInSheet=5|OwnerPartId=-1|Location.X=527|Location.X_Frac=50000|Location.Y=752|Color=8388608|FontID=2|IsHidden=T|Text=85C|Name=MAXTEMP
|RECORD=41|OwnerIndex=92|IndexInSheet=6|OwnerPartId=-1|Location.X=527|Location.X_Frac=50000|Location.Y=752|Color=8388608|FontID=2|IsHidden=T|Text=-25C|Name=MINTEMP
|RECORD=41|OwnerIndex=92|IndexInSheet=7|OwnerPartId=-1|Location.X=527|Location.X_Frac=50000|Location.Y=752|Color=8388608|FontID=2|IsHidden=T|Text=SML-LX0603|Name=OTHER
|RECORD=41|OwnerIndex=92|IndexInSheet=8|OwnerPartId=-1|Location.X=527|Location.X_Frac=50000|Location.Y=752|Color=8388608|FontID=2|IsHidden=T|Text=635NM|Name=P1
|RECORD=41|OwnerIndex=92|IndexInSheet=9|OwnerPartId=-1|Location.X=527|Location.X_Frac=50000|Location.Y=752|Color=8388608|FontID=2|IsHidden=T|Text=2V|Name=P2
|RECORD=41|OwnerIndex=92|IndexInSheet=10|OwnerPartId=-1|Location.X=527|Location.X_Frac=50000|Location.Y=752|Color=8388608|FontID=2|IsHidden=T|Text=20MA|Name=P3
|RECORD=41|OwnerIndex=92|IndexInSheet=11|OwnerPartId=-1|Location.X=527|Location.X_Frac=50000|Location.Y=752|Color=8388608|FontID=2|IsHidden=T|Name=SUB
|RECORD=41|OwnerIndex=92|IndexInSheet=12|OwnerPartId=-1|Location.X=527|Location.X_Frac=50000|Location.Y=752|Color=8388608|FontID=2|IsHidden=T|Text=0603|Name=SIZE
|RECORD=41|OwnerIndex=92|IndexInSheet=13|OwnerPartId=-1|Location.X=527|Location.X_Frac=50000|Location.Y=752|Color=8388608|FontID=1|IsHidden=T|Text=*|Name=SHEETPART
|RECORD=41|OwnerIndex=92|IndexInSheet=14|OwnerPartId=-1|Location.X=527|Location.X_Frac=50000|Location.Y=752|Color=8388608|FontID=1|IsHidden=T|Text=LED, RED, SML-LX0603, 635NM, 2V, 20MA, 0603|Name=DESC
|RECORD=41|OwnerIndex=92|IndexInSheet=15|OwnerPartId=-1|Location.X=527|Location.X_Frac=50000|Location.Y=752|Color=8388608|FontID=1|IsHidden=T|Text=Digi-Key|Name=Supplier 1|ReadOnlyState=3
|RECORD=41|OwnerIndex=92|IndexInSheet=16|OwnerPartId=-1|Location.X=527|Location.X_Frac=50000|Location.Y=752|Color=8388608|FontID=1|IsHidden=T|Text=67-1548-1-ND|Name=Supplier Part Number 1|ReadOnlyState=3
|RECORD=41|OwnerIndex=92|IndexInSheet=17|OwnerPartId=-1|Location.X=560|Location.Y=706|Location.Y_Frac=50000|Color=8388608|FontID=2|Text=RED|Name=VALUE
|RECORD=2|OwnerIndex=92|OwnerPartId=1|FormalType=1|Electrical=4|PinConglomerate=33|PinLength=20|Location.X=540|Location.Y=730|Name=A|Designator=2|PinPropagationDelay=0.000000E+000
|RECORD=2|OwnerIndex=92|OwnerPartId=1|FormalType=1|Electrical=4|PinConglomerate=35|PinLength=20|Location.X=540|Location.Y=710|Name=K|Designator=1|PinPropagationDelay=0.000000E+000
|RECORD=12|OwnerIndex=92|IsNotAccesible=T|IndexInSheet=20|OwnerPartId=1|Location.X=540|Location.Y=720|Radius=12|Radius_Frac=50000|LineWidth=1|EndAngle=360.000|Color=16711680
|RECORD=13|OwnerIndex=92|IsNotAccesible=T|IndexInSheet=21|OwnerPartId=1|Location.X=548|Location.Y=714|Corner.X=533|Corner.Y=714|LineWidth=1|Color=16711680
|RECORD=13|OwnerIndex=92|IsNotAccesible=T|IndexInSheet=22|OwnerPartId=1|Location.X=555|Location.Y=701|Corner.X=548|Corner.X_Frac=70000|Corner.Y=707|Corner.Y_Frac=20000|LineWidth=1|Color=16711680
|RECORD=13|OwnerIndex=92|IsNotAccesible=T|IndexInSheet=23|OwnerPartId=1|Location.X=559|Location.Y=705|Corner.X=552|Corner.X_Frac=80000|Corner.Y=711|Corner.Y_Frac=30000|LineWidth=1|Color=16711680
|RECORD=13|OwnerIndex=92|IsNotAccesible=T|IndexInSheet=24|OwnerPartId=1|Location.X=540|Location.Y=710|Corner.X=540|Corner.Y=713|Corner.Y_Frac=80000|LineWidth=1|Color=16711680
|RECORD=13|OwnerIndex=92|IsNotAccesible=T|IndexInSheet=25|OwnerPartId=1|Location.X=540|Location.Y=726|Corner.X=540|Corner.Y=729|Corner.Y_Frac=70000|LineWidth=1|Color=16711680
|RECORD=7|OwnerIndex=92|IsNotAccesible=T|IndexInSheet=26|OwnerPartId=1|LineWidth=1|Color=16711680|AreaColor=16711680|IsSolid=T|LocationCount=3|X1=554|Y1=704|X2=552|Y2=702|X3=555|Y3=701
|RECORD=7|OwnerIndex=92|IsNotAccesible=T|IndexInSheet=27|OwnerPartId=1|LineWidth=1|Color=16711680|AreaColor=16711680|IsSolid=T|LocationCount=3|X1=558|Y1=708|X2=556|Y2=706|X3=559|Y3=705
|RECORD=7|OwnerIndex=92|IsNotAccesible=T|IndexInSheet=28|OwnerPartId=1|LineWidth=1|Color=16711680|AreaColor=16777215|IsSolid=T|LocationCount=3|X1=540|Y1=714|X2=548|Y2=726|X3=532|Y3=726
|RECORD=41|OwnerIndex=92|IndexInSheet=29|OwnerPartId=-1|Location.X=527|Location.X_Frac=50000|Location.Y=752|Color=8388608|FontID=1|IsHidden=T|Text=<VALENTIUM>|Name=VALENTIUM PART NUM
|RECORD=34|OwnerIndex=92|IndexInSheet=-1|OwnerPartId=-1|Location.X=560|Location.Y=718|Location.Y_Frac=50000|Color=8388608|FontID=3|Text=D13|Name=Designator|ReadOnlyState=1
|RECORD=41|OwnerIndex=92|IndexInSheet=-1|OwnerPartId=-1|Location.X=527|Location.X_Frac=50000|Location.Y=752|Color=8388608|FontID=2|IsHidden=T|Text==VALUE|Name=Comment|ReadOnlyState=1
|RECORD=44|OwnerIndex=92
|RECORD=45|OwnerIndex=127|IndexInSheet=-1|Description=Molded Diode, 0603, 2-Leads, Body 1.60x0.80mm, IPC Medium Density|UseComponentLibrary=T|ModelName=DIOM1608X06N|ModelType=PCBLIB|DatafileCount=1|ModelDatafileEntity0=DIOM1608X06N|ModelDatafileKind0=PCBLib|IsCurrent=T|DatalinksLocked=T|DatabaseDatalinksLocked=T|IntegratedModel=T|DatabaseModel=T
|RECORD=46|OwnerIndex=128
|RECORD=48|OwnerIndex=128
|RECORD=1|LibReference=SMTLED_RED_0603_SML|ComponentDescription=LED, RED, SML-LX0603, 635NM, 2V, 20MA, 0603|PartCount=2|DisplayModeCount=1|IndexInSheet=44|OwnerPartId=-1|Location.X=440|Location.Y=750|Orientation=3|CurrentPartId=1|LibraryPath=*|SourceLibraryName=Passives.IntLib|TargetFileName=*|AreaColor=11599871|Color=128|PartIDLocked=F|DesignItemId=SMTLED_RED_0603_SML|AllPinCount=2
|RECORD=41|OwnerIndex=131|OwnerPartId=-1|Location.X=427|Location.X_Frac=50000|Location.Y=752|Color=8388608|FontID=2|IsHidden=T|Text=SML-LX0603IW-TR|Name=MFG PART NUM
|RECORD=41|OwnerIndex=131|IndexInSheet=1|OwnerPartId=-1|Location.X=427|Location.X_Frac=50000|Location.Y=752|Color=8388608|FontID=2|IsHidden=T|Text=9/4/2013|Name=MODIFY DATE
|RECORD=41|OwnerIndex=131|IndexInSheet=2|OwnerPartId=-1|Location.X=427|Location.X_Frac=50000|Location.Y=752|Color=8388608|FontID=2|IsHidden=T|Text=LUMEX|Name=MFG NAME
|RECORD=41|OwnerIndex=131|IndexInSheet=3|OwnerPartId=-1|Location.X=427|Location.X_Frac=50000|Location.Y=752|Color=8388608|FontID=2|IsHidden=T|Text=LED|Name=CATEGORY
|RECORD=41|OwnerIndex=131|IndexInSheet=4|OwnerPartId=-1|Location.X=427|Location.X_Frac=50000|Location.Y=752|Color=8388608|FontID=2|IsHidden=T|Name=Date
|RECORD=41|OwnerIndex=131|IndexInSheet=5|OwnerPartId=-1|Location.X=427|Location.X_Frac=50000|Location.Y=752|Color=8388608|FontID=2|IsHidden=T|Text=85C|Name=MAXTEMP
|RECORD=41|OwnerIndex=131|IndexInSheet=6|OwnerPartId=-1|Location.X=427|Location.X_Frac=50000|Location.Y=752|Color=8388608|FontID=2|IsHidden=T|Text=-25C|Name=MINTEMP
|RECORD=41|OwnerIndex=131|IndexInSheet=7|OwnerPartId=-1|Location.X=427|Location.X_Frac=50000|Location.Y=752|Color=8388608|FontID=2|IsHidden=T|Text=SML-LX0603|Name=OTHER
|RECORD=41|OwnerIndex=131|IndexInSheet=8|OwnerPartId=-1|Location.X=427|Location.X_Frac=50000|Location.Y=752|Color=8388608|FontID=2|IsHidden=T|Text=635NM|Name=P1
|RECORD=41|OwnerIndex=131|IndexInSheet=9|OwnerPartId=-1|Location.X=427|Location.X_Frac=50000|Location.Y=752|Color=8388608|FontID=2|IsHidden=T|Text=2V|Name=P2
|RECORD=41|OwnerIndex=131|IndexInSheet=10|OwnerPartId=-1|Location.X=427|Location.X_Frac=50000|Location.Y=752|Color=8388608|FontID=2|IsHidden=T|Text=20MA|Name=P3
|RECORD=41|OwnerIndex=131|IndexInSheet=11|OwnerPartId=-1|Location.X=427|Location.X_Frac=50000|Location.Y=752|Color=8388608|FontID=2|IsHidden=T|Name=SUB
|RECORD=41|OwnerIndex=131|IndexInSheet=12|OwnerPartId=-1|Location.X=427|Location.X_Frac=50000|Location.Y=752|Color=8388608|FontID=2|IsHidden=T|Text=0603|Name=SIZE
|RECORD=41|OwnerIndex=131|IndexInSheet=13|OwnerPartId=-1|Location.X=427|Location.X_Frac=50000|Location.Y=752|Color=8388608|FontID=1|IsHidden=T|Text=*|Name=SHEETPART
|RECORD=41|OwnerIndex=131|IndexInSheet=14|OwnerPartId=-1|Location.X=427|Location.X_Frac=50000|Location.Y=752|Color=8388608|FontID=1|IsHidden=T|Text=LED, RED, SML-LX0603, 635NM, 2V, 20MA, 0603|Name=DESC
|RECORD=41|OwnerIndex=131|IndexInSheet=15|OwnerPartId=-1|Location.X=427|Location.X_Frac=50000|Location.Y=752|Color=8388608|FontID=1|IsHidden=T|Text=Digi-Key|Name=Supplier 1|ReadOnlyState=3
|RECORD=41|OwnerIndex=131|IndexInSheet=16|OwnerPartId=-1|Location.X=427|Location.X_Frac=50000|Location.Y=752|Color=8388608|FontID=1|IsHidden=T|Text=67-1548-1-ND|Name=Supplier Part Number 1|ReadOnlyState=3
|RECORD=41|OwnerIndex=131|IndexInSheet=17|OwnerPartId=-1|Location.X=460|Location.Y=706|Location.Y_Frac=50000|Color=8388608|FontID=2|Text=RED|Name=VALUE
|RECORD=2|OwnerIndex=131|OwnerPartId=1|FormalType=1|Electrical=4|PinConglomerate=33|PinLength=20|Location.X=440|Location.Y=730|Name=A|Designator=2|PinPropagationDelay=0.000000E+000
|RECORD=2|OwnerIndex=131|OwnerPartId=1|FormalType=1|Electrical=4|PinConglomerate=35|PinLength=20|Location.X=440|Location.Y=710|Name=K|Designator=1|PinPropagationDelay=0.000000E+000
|RECORD=12|OwnerIndex=131|IsNotAccesible=T|IndexInSheet=20|OwnerPartId=1|Location.X=440|Location.Y=720|Radius=12|Radius_Frac=50000|LineWidth=1|EndAngle=360.000|Color=16711680
|RECORD=13|OwnerIndex=131|IsNotAccesible=T|IndexInSheet=21|OwnerPartId=1|Location.X=448|Location.Y=714|Corner.X=433|Corner.Y=714|LineWidth=1|Color=16711680
|RECORD=13|OwnerIndex=131|IsNotAccesible=T|IndexInSheet=22|OwnerPartId=1|Location.X=455|Location.Y=701|Corner.X=448|Corner.X_Frac=70000|Corner.Y=707|Corner.Y_Frac=20000|LineWidth=1|Color=16711680
|RECORD=13|OwnerIndex=131|IsNotAccesible=T|IndexInSheet=23|OwnerPartId=1|Location.X=459|Location.Y=705|Corner.X=452|Corner.X_Frac=80000|Corner.Y=711|Corner.Y_Frac=30000|LineWidth=1|Color=16711680
|RECORD=13|OwnerIndex=131|IsNotAccesible=T|IndexInSheet=24|OwnerPartId=1|Location.X=440|Location.Y=710|Corner.X=440|Corner.Y=713|Corner.Y_Frac=80000|LineWidth=1|Color=16711680
|RECORD=13|OwnerIndex=131|IsNotAccesible=T|IndexInSheet=25|OwnerPartId=1|Location.X=440|Location.Y=726|Corner.X=440|Corner.Y=729|Corner.Y_Frac=70000|LineWidth=1|Color=16711680
|RECORD=7|OwnerIndex=131|IsNotAccesible=T|IndexInSheet=26|OwnerPartId=1|LineWidth=1|Color=16711680|AreaColor=16711680|IsSolid=T|LocationCount=3|X1=454|Y1=704|X2=452|Y2=702|X3=455|Y3=701
|RECORD=7|OwnerIndex=131|IsNotAccesible=T|IndexInSheet=27|OwnerPartId=1|LineWidth=1|Color=16711680|AreaColor=16711680|IsSolid=T|LocationCount=3|X1=458|Y1=708|X2=456|Y2=706|X3=459|Y3=705
|RECORD=7|OwnerIndex=131|IsNotAccesible=T|IndexInSheet=28|OwnerPartId=1|LineWidth=1|Color=16711680|AreaColor=16777215|IsSolid=T|LocationCount=3|X1=440|Y1=714|X2=448|Y2=726|X3=432|Y3=726
|RECORD=41|OwnerIndex=131|IndexInSheet=29|OwnerPartId=-1|Location.X=427|Location.X_Frac=50000|Location.Y=752|Color=8388608|FontID=1|IsHidden=T|Text=<VALENTIUM>|Name=VALENTIUM PART NUM
|RECORD=34|OwnerIndex=131|IndexInSheet=-1|OwnerPartId=-1|Location.X=460|Location.Y=718|Location.Y_Frac=50000|Color=8388608|FontID=3|Text=D12|Name=Designator|ReadOnlyState=1
|RECORD=41|OwnerIndex=131|IndexInSheet=-1|OwnerPartId=-1|Location.X=427|Location.X_Frac=50000|Location.Y=752|Color=8388608|FontID=2|IsHidden=T|Text==VALUE|Name=Comment|ReadOnlyState=1
|RECORD=44|OwnerIndex=131
|RECORD=45|OwnerIndex=166|IndexInSheet=-1|Description=Molded Diode, 0603, 2-Leads, Body 1.60x0.80mm, IPC Medium Density|UseComponentLibrary=T|ModelName=DIOM1608X06N|ModelType=PCBLIB|DatafileCount=1|ModelDatafileEntity0=DIOM1608X06N|ModelDatafileKind0=PCBLib|IsCurrent=T|DatalinksLocked=T|DatabaseDatalinksLocked=T|IntegratedModel=T|DatabaseModel=T
|RECORD=46|OwnerIndex=167
|RECORD=48|OwnerIndex=167
|RECORD=1|LibReference=SMTLED_RED_0603_SML|ComponentDescription=LED, RED, SML-LX0603, 635NM, 2V, 20MA, 0603|PartCount=2|DisplayModeCount=1|IndexInSheet=45|OwnerPartId=-1|Location.X=340|Location.Y=750|Orientation=3|CurrentPartId=1|LibraryPath=*|SourceLibraryName=Passives.IntLib|TargetFileName=*|AreaColor=11599871|Color=128|PartIDLocked=F|DesignItemId=SMTLED_RED_0603_SML|AllPinCount=2
|RECORD=41|OwnerIndex=170|OwnerPartId=-1|Location.X=327|Location.X_Frac=50000|Location.Y=752|Color=8388608|FontID=2|IsHidden=T|Text=SML-LX0603IW-TR|Name=MFG PART NUM
|RECORD=41|OwnerIndex=170|IndexInSheet=1|OwnerPartId=-1|Location.X=327|Location.X_Frac=50000|Location.Y=752|Color=8388608|FontID=2|IsHidden=T|Text=9/4/2013|Name=MODIFY DATE
|RECORD=41|OwnerIndex=170|IndexInSheet=2|OwnerPartId=-1|Location.X=327|Location.X_Frac=50000|Location.Y=752|Color=8388608|FontID=2|IsHidden=T|Text=LUMEX|Name=MFG NAME
|RECORD=41|OwnerIndex=170|IndexInSheet=3|OwnerPartId=-1|Location.X=327|Location.X_Frac=50000|Location.Y=752|Color=8388608|FontID=2|IsHidden=T|Text=LED|Name=CATEGORY
|RECORD=41|OwnerIndex=170|IndexInSheet=4|OwnerPartId=-1|Location.X=327|Location.X_Frac=50000|Location.Y=752|Color=8388608|FontID=2|IsHidden=T|Name=Date
|RECORD=41|OwnerIndex=170|IndexInSheet=5|OwnerPartId=-1|Location.X=327|Location.X_Frac=50000|Location.Y=752|Color=8388608|FontID=2|IsHidden=T|Text=85C|Name=MAXTEMP
|RECORD=41|OwnerIndex=170|IndexInSheet=6|OwnerPartId=-1|Location.X=327|Location.X_Frac=50000|Location.Y=752|Color=8388608|FontID=2|IsHidden=T|Text=-25C|Name=MINTEMP
|RECORD=41|OwnerIndex=170|IndexInSheet=7|OwnerPartId=-1|Location.X=327|Location.X_Frac=50000|Location.Y=752|Color=8388608|FontID=2|IsHidden=T|Text=SML-LX0603|Name=OTHER
|RECORD=41|OwnerIndex=170|IndexInSheet=8|OwnerPartId=-1|Location.X=327|Location.X_Frac=50000|Location.Y=752|Color=8388608|FontID=2|IsHidden=T|Text=635NM|Name=P1
|RECORD=41|OwnerIndex=170|IndexInSheet=9|OwnerPartId=-1|Location.X=327|Location.X_Frac=50000|Location.Y=752|Color=8388608|FontID=2|IsHidden=T|Text=2V|Name=P2
|RECORD=41|OwnerIndex=170|IndexInSheet=10|OwnerPartId=-1|Location.X=327|Location.X_Frac=50000|Location.Y=752|Color=8388608|FontID=2|IsHidden=T|Text=20MA|Name=P3
|RECORD=41|OwnerIndex=170|IndexInSheet=11|OwnerPartId=-1|Location.X=327|Location.X_Frac=50000|Location.Y=752|Color=8388608|FontID=2|IsHidden=T|Name=SUB
|RECORD=41|OwnerIndex=170|IndexInSheet=12|OwnerPartId=-1|Location.X=327|Location.X_Frac=50000|Location.Y=752|Color=8388608|FontID=2|IsHidden=T|Text=0603|Name=SIZE
|RECORD=41|OwnerIndex=170|IndexInSheet=13|OwnerPartId=-1|Location.X=327|Location.X_Frac=50000|Location.Y=752|Color=8388608|FontID=1|IsHidden=T|Text=*|Name=SHEETPART
|RECORD=41|OwnerIndex=170|IndexInSheet=14|OwnerPartId=-1|Location.X=327|Location.X_Frac=50000|Location.Y=752|Color=8388608|FontID=1|IsHidden=T|Text=LED, RED, SML-LX0603, 635NM, 2V, 20MA, 0603|Name=DESC
|RECORD=41|OwnerIndex=170|IndexInSheet=15|OwnerPartId=-1|Location.X=327|Location.X_Frac=50000|Location.Y=752|Color=8388608|FontID=1|IsHidden=T|Text=Digi-Key|Name=Supplier 1|ReadOnlyState=3
|RECORD=41|OwnerIndex=170|IndexInSheet=16|OwnerPartId=-1|Location.X=327|Location.X_Frac=50000|Location.Y=752|Color=8388608|FontID=1|IsHidden=T|Text=67-1548-1-ND|Name=Supplier Part Number 1|ReadOnlyState=3
|RECORD=41|OwnerIndex=170|IndexInSheet=17|OwnerPartId=-1|Location.X=360|Location.Y=706|Location.Y_Frac=50000|Color=8388608|FontID=2|Text=RED|Name=VALUE
|RECORD=2|OwnerIndex=170|OwnerPartId=1|FormalType=1|Electrical=4|PinConglomerate=33|PinLength=20|Location.X=340|Location.Y=730|Name=A|Designator=2|PinPropagationDelay=0.000000E+000
|RECORD=2|OwnerIndex=170|OwnerPartId=1|FormalType=1|Electrical=4|PinConglomerate=35|PinLength=20|Location.X=340|Location.Y=710|Name=K|Designator=1|PinPropagationDelay=0.000000E+000
|RECORD=12|OwnerIndex=170|IsNotAccesible=T|IndexInSheet=20|OwnerPartId=1|Location.X=340|Location.Y=720|Radius=12|Radius_Frac=50000|LineWidth=1|EndAngle=360.000|Color=16711680
|RECORD=13|OwnerIndex=170|IsNotAccesible=T|IndexInSheet=21|OwnerPartId=1|Location.X=348|Location.Y=714|Corner.X=333|Corner.Y=714|LineWidth=1|Color=16711680
|RECORD=13|OwnerIndex=170|IsNotAccesible=T|IndexInSheet=22|OwnerPartId=1|Location.X=355|Location.Y=701|Corner.X=348|Corner.X_Frac=70000|Corner.Y=707|Corner.Y_Frac=20000|LineWidth=1|Color=16711680
|RECORD=13|OwnerIndex=170|IsNotAccesible=T|IndexInSheet=23|OwnerPartId=1|Location.X=359|Location.Y=705|Corner.X=352|Corner.X_Frac=80000|Corner.Y=711|Corner.Y_Frac=30000|LineWidth=1|Color=16711680
|RECORD=13|OwnerIndex=170|IsNotAccesible=T|IndexInSheet=24|OwnerPartId=1|Location.X=340|Location.Y=710|Corner.X=340|Corner.Y=713|Corner.Y_Frac=80000|LineWidth=1|Color=16711680
|RECORD=13|OwnerIndex=170|IsNotAccesible=T|IndexInSheet=25|OwnerPartId=1|Location.X=340|Location.Y=726|Corner.X=340|Corner.Y=729|Corner.Y_Frac=70000|LineWidth=1|Color=16711680
|RECORD=7|OwnerIndex=170|IsNotAccesible=T|IndexInSheet=26|OwnerPartId=1|LineWidth=1|Color=16711680|AreaColor=16711680|IsSolid=T|LocationCount=3|X1=354|Y1=704|X2=352|Y2=702|X3=355|Y3=701
|RECORD=7|OwnerIndex=170|IsNotAccesible=T|IndexInSheet=27|OwnerPartId=1|LineWidth=1|Color=16711680|AreaColor=16711680|IsSolid=T|LocationCount=3|X1=358|Y1=708|X2=356|Y2=706|X3=359|Y3=705
|RECORD=7|OwnerIndex=170|IsNotAccesible=T|IndexInSheet=28|OwnerPartId=1|LineWidth=1|Color=16711680|AreaColor=16777215|IsSolid=T|LocationCount=3|X1=340|Y1=714|X2=348|Y2=726|X3=332|Y3=726
|RECORD=41|OwnerIndex=170|IndexInSheet=29|OwnerPartId=-1|Location.X=327|Location.X_Frac=50000|Location.Y=752|Color=8388608|FontID=1|IsHidden=T|Text=<VALENTIUM>|Name=VALENTIUM PART NUM
|RECORD=34|OwnerIndex=170|IndexInSheet=-1|OwnerPartId=-1|Location.X=360|Location.Y=718|Location.Y_Frac=50000|Color=8388608|FontID=3|Text=D11|Name=Designator|ReadOnlyState=1
|RECORD=41|OwnerIndex=170|IndexInSheet=-1|OwnerPartId=-1|Location.X=327|Location.X_Frac=50000|Location.Y=752|Color=8388608|FontID=2|IsHidden=T|Text==VALUE|Name=Comment|ReadOnlyState=1
|RECORD=44|OwnerIndex=170
|RECORD=45|OwnerIndex=205|IndexInSheet=-1|Description=Molded Diode, 0603, 2-Leads, Body 1.60x0.80mm, IPC Medium Density|UseComponentLibrary=T|ModelName=DIOM1608X06N|ModelType=PCBLIB|DatafileCount=1|ModelDatafileEntity0=DIOM1608X06N|ModelDatafileKind0=PCBLib|IsCurrent=T|DatalinksLocked=T|DatabaseDatalinksLocked=T|IntegratedModel=T|DatabaseModel=T
|RECORD=46|OwnerIndex=206
|RECORD=48|OwnerIndex=206
|RECORD=1|LibReference=RES_0603_1.0K|ComponentDescription=RES, 1.0K, 1%, 1/10W, TF, 0603|PartCount=2|DisplayModeCount=1|IndexInSheet=46|OwnerPartId=-1|Location.X=520|Location.Y=420|CurrentPartId=1|LibraryPath=*|SourceLibraryName=Resistors.IntLib|TargetFileName=*|AreaColor=11599871|Color=128|PartIDLocked=F|DesignItemId=RES_0603_1.0K|AllPinCount=2
|RECORD=41|OwnerIndex=209|OwnerPartId=-1|Location.X=520|Location.Y=420|Color=8388608|FontID=2|IsHidden=T|Text=7/25/2013|Name=ModifyDate
|RECORD=41|OwnerIndex=209|IndexInSheet=1|OwnerPartId=-1|Location.X=520|Location.Y=420|Color=8388608|FontID=2|IsHidden=T|Text=ERJ-3EKF1001V|Name=MFG PART NUM
|RECORD=41|OwnerIndex=209|IndexInSheet=2|OwnerPartId=-1|Location.X=520|Location.Y=420|Color=8388608|FontID=2|IsHidden=T|Text=PANASONIC|Name=MFG NAME
|RECORD=41|OwnerIndex=209|IndexInSheet=3|OwnerPartId=-1|Location.X=520|Location.Y=420|Color=8388608|FontID=2|IsHidden=T|Text=RES|Name=CATEGORY
|RECORD=41|OwnerIndex=209|IndexInSheet=4|OwnerPartId=-1|Location.X=518|Location.Y=430|Color=8388608|FontID=2|IsHidden=T|Text=7/26/2013|Name=Date
|RECORD=41|OwnerIndex=209|IndexInSheet=5|OwnerPartId=-1|Location.X=510|Location.X_Frac=55769|Location.Y=430|Color=8388608|FontID=2|IsHidden=T|Text=1%|Name=P1
|RECORD=41|OwnerIndex=209|IndexInSheet=6|OwnerPartId=-1|Location.X=510|Location.X_Frac=55769|Location.Y=430|Color=8388608|FontID=2|IsHidden=T|Text=TF|Name=P3
|RECORD=41|OwnerIndex=209|IndexInSheet=7|OwnerPartId=-1|Location.X=510|Location.X_Frac=55769|Location.Y=430|Color=8388608|FontID=2|IsHidden=T|Text=1/10W|Name=P2
|RECORD=41|OwnerIndex=209|IndexInSheet=8|OwnerPartId=-1|Location.X=510|Location.X_Frac=55769|Location.Y=430|Color=8388608|FontID=2|IsHidden=T|Text=125C|Name=MAXTEMP
|RECORD=41|OwnerIndex=209|IndexInSheet=9|OwnerPartId=-1|Location.X=510|Location.X_Frac=55769|Location.Y=430|Color=8388608|FontID=2|IsHidden=T|Text=-55C|Name=MINTEMP
|RECORD=41|OwnerIndex=209|IndexInSheet=10|OwnerPartId=-1|Location.X=510|Location.X_Frac=55769|Location.Y=430|Color=8388608|FontID=2|IsHidden=T|Text=100PPM|Name=OTHER
|RECORD=41|OwnerIndex=209|IndexInSheet=11|OwnerPartId=-1|Location.X=510|Location.X_Frac=55769|Location.Y=430|Color=8388608|FontID=2|IsHidden=T|Text=0603|Name=SIZE
|RECORD=41|OwnerIndex=209|IndexInSheet=12|OwnerPartId=-1|Location.X=510|Location.X_Frac=55769|Location.Y=430|Color=8388608|FontID=2|IsHidden=T|Text=GENERIC|Name=SUB
|RECORD=41|OwnerIndex=209|IndexInSheet=13|OwnerPartId=-1|Location.X=510|Location.X_Frac=55769|Location.Y=430|Color=8388608|FontID=2|IsHidden=T|Text=Digi-Key|Name=Supplier 1|ReadOnlyState=3
|RECORD=41|OwnerIndex=209|IndexInSheet=14|OwnerPartId=-1|Location.X=510|Location.X_Frac=55769|Location.Y=430|Color=8388608|FontID=2|IsHidden=T|Text=P1.00KHCT-ND|Name=Supplier Part Number 1|ReadOnlyState=3
|RECORD=41|OwnerIndex=209|IndexInSheet=15|OwnerPartId=-1|Location.X=505|Location.X_Frac=98077|Location.Y=406|Color=8388608|FontID=1|IsHidden=T|Text=*|Name=SHEETPART
|RECORD=41|OwnerIndex=209|IndexInSheet=16|OwnerPartId=-1|Location.X=505|Location.X_Frac=98077|Location.Y=434|Color=8388608|FontID=1|IsHidden=T|Text=RES, 1.0K, 1%, 1/10W, TF, 0603|Name=DESC
|RECORD=41|OwnerIndex=209|IndexInSheet=17|OwnerPartId=-1|Location.X=529|Location.Y=404|Color=8388608|FontID=2|Text=1.0K|Name=VALUE
|RECORD=2|OwnerIndex=209|OwnerPartId=1|FormalType=1|Electrical=4|PinConglomerate=34|PinLength=10|Location.X=530|Location.Y=420|Name=1|Designator=1|PinPropagationDelay=0.000000E+000
|RECORD=2|OwnerIndex=209|OwnerPartId=1|FormalType=1|Electrical=4|PinConglomerate=32|PinLength=10|Location.X=560|Location.Y=420|Name=2|Designator=2|PinPropagationDelay=0.000000E+000
|RECORD=6|OwnerIndex=209|IsNotAccesible=T|IndexInSheet=20|OwnerPartId=1|LineWidth=1|Color=16711680|LocationCount=7|X1=560|Y1=420|X2=557|Y2=423|X3=551|Y3=417|X4=545|Y4=423|X5=539|Y5=417|X6=533|Y6=423|X7=530|Y7=420
|RECORD=41|OwnerIndex=209|IndexInSheet=21|OwnerPartId=-1|Location.X=506|Location.X_Frac=61102|Location.Y=434|Color=8388608|FontID=1|IsHidden=T|Text=<VELENTIUM>|Name=VELENTIUM PART NUM
|RECORD=34|OwnerIndex=209|IndexInSheet=-1|OwnerPartId=-1|Location.X=529|Location.Y=424|Color=8388608|FontID=3|Text=R36|Name=Designator|ReadOnlyState=1
|RECORD=41|OwnerIndex=209|IndexInSheet=-1|OwnerPartId=-1|Location.X=540|Location.Y=410|Color=8388608|FontID=2|IsHidden=T|Text==MFG PART NUM|Name=Comment
|RECORD=44|OwnerIndex=209
|RECORD=45|OwnerIndex=236|IndexInSheet=-1|Description=Chip Resistor, 0603, 2-Leads, Body 1.57x0.85mm, IPC Medium Density|UseComponentLibrary=T|ModelName=RESC1608X50N|ModelType=PCBLIB|DatafileCount=1|ModelDatafileEntity0=RESC1608X50N|ModelDatafileKind0=PCBLib|IsCurrent=T|DatalinksLocked=T|DatabaseDatalinksLocked=T|IntegratedModel=T|DatabaseModel=T
|RECORD=46|OwnerIndex=237
|RECORD=48|OwnerIndex=237
|RECORD=1|LibReference=RES_0603_1.0K|ComponentDescription=RES, 1.0K, 1%, 1/10W, TF, 0603|PartCount=2|DisplayModeCount=1|IndexInSheet=47|OwnerPartId=-1|Location.X=210|Location.Y=420|CurrentPartId=1|LibraryPath=*|SourceLibraryName=Resistors.IntLib|TargetFileName=*|AreaColor=11599871|Color=128|PartIDLocked=F|DesignItemId=RES_0603_1.0K|AllPinCount=2
|RECORD=41|OwnerIndex=240|OwnerPartId=-1|Location.X=210|Location.Y=420|Color=8388608|FontID=2|IsHidden=T|Text=7/25/2013|Name=ModifyDate
|RECORD=41|OwnerIndex=240|IndexInSheet=1|OwnerPartId=-1|Location.X=210|Location.Y=420|Color=8388608|FontID=2|IsHidden=T|Text=ERJ-3EKF1001V|Name=MFG PART NUM
|RECORD=41|OwnerIndex=240|IndexInSheet=2|OwnerPartId=-1|Location.X=210|Location.Y=420|Color=8388608|FontID=2|IsHidden=T|Text=PANASONIC|Name=MFG NAME
|RECORD=41|OwnerIndex=240|IndexInSheet=3|OwnerPartId=-1|Location.X=210|Location.Y=420|Color=8388608|FontID=2|IsHidden=T|Text=RES|Name=CATEGORY
|RECORD=41|OwnerIndex=240|IndexInSheet=4|OwnerPartId=-1|Location.X=208|Location.Y=430|Color=8388608|FontID=2|IsHidden=T|Text=7/26/2013|Name=Date
|RECORD=41|OwnerIndex=240|IndexInSheet=5|OwnerPartId=-1|Location.X=200|Location.X_Frac=55769|Location.Y=430|Color=8388608|FontID=2|IsHidden=T|Text=1%|Name=P1
|RECORD=41|OwnerIndex=240|IndexInSheet=6|OwnerPartId=-1|Location.X=200|Location.X_Frac=55769|Location.Y=430|Color=8388608|FontID=2|IsHidden=T|Text=TF|Name=P3
|RECORD=41|OwnerIndex=240|IndexInSheet=7|OwnerPartId=-1|Location.X=200|Location.X_Frac=55769|Location.Y=430|Color=8388608|FontID=2|IsHidden=T|Text=1/10W|Name=P2
|RECORD=41|OwnerIndex=240|IndexInSheet=8|OwnerPartId=-1|Location.X=200|Location.X_Frac=55769|Location.Y=430|Color=8388608|FontID=2|IsHidden=T|Text=125C|Name=MAXTEMP
|RECORD=41|OwnerIndex=240|IndexInSheet=9|OwnerPartId=-1|Location.X=200|Location.X_Frac=55769|Location.Y=430|Color=8388608|FontID=2|IsHidden=T|Text=-55C|Name=MINTEMP
|RECORD=41|OwnerIndex=240|IndexInSheet=10|OwnerPartId=-1|Location.X=200|Location.X_Frac=55769|Location.Y=430|Color=8388608|FontID=2|IsHidden=T|Text=100PPM|Name=OTHER
|RECORD=41|OwnerIndex=240|IndexInSheet=11|OwnerPartId=-1|Location.X=200|Location.X_Frac=55769|Location.Y=430|Color=8388608|FontID=2|IsHidden=T|Text=0603|Name=SIZE
|RECORD=41|OwnerIndex=240|IndexInSheet=12|OwnerPartId=-1|Location.X=200|Location.X_Frac=55769|Location.Y=430|Color=8388608|FontID=2|IsHidden=T|Text=GENERIC|Name=SUB
|RECORD=41|OwnerIndex=240|IndexInSheet=13|OwnerPartId=-1|Location.X=200|Location.X_Frac=55769|Location.Y=430|Color=8388608|FontID=2|IsHidden=T|Text=Digi-Key|Name=Supplier 1|ReadOnlyState=3
|RECORD=41|OwnerIndex=240|IndexInSheet=14|OwnerPartId=-1|Location.X=200|Location.X_Frac=55769|Location.Y=430|Color=8388608|FontID=2|IsHidden=T|Text=P1.00KHCT-ND|Name=Supplier Part Number 1|ReadOnlyState=3
|RECORD=41|OwnerIndex=240|IndexInSheet=15|OwnerPartId=-1|Location.X=195|Location.X_Frac=98077|Location.Y=406|Color=8388608|FontID=1|IsHidden=T|Text=*|Name=SHEETPART
|RECORD=41|OwnerIndex=240|IndexInSheet=16|OwnerPartId=-1|Location.X=195|Location.X_Frac=98077|Location.Y=434|Color=8388608|FontID=1|IsHidden=T|Text=RES, 1.0K, 1%, 1/10W, TF, 0603|Name=DESC
|RECORD=41|OwnerIndex=240|IndexInSheet=17|OwnerPartId=-1|Location.X=219|Location.Y=404|Color=8388608|FontID=2|Text=1.0K|Name=VALUE
|RECORD=2|OwnerIndex=240|OwnerPartId=1|FormalType=1|Electrical=4|PinConglomerate=34|PinLength=10|Location.X=220|Location.Y=420|Name=1|Designator=1|PinPropagationDelay=0.000000E+000
|RECORD=2|OwnerIndex=240|OwnerPartId=1|FormalType=1|Electrical=4|PinConglomerate=32|PinLength=10|Location.X=250|Location.Y=420|Name=2|Designator=2|PinPropagationDelay=0.000000E+000
|RECORD=6|OwnerIndex=240|IsNotAccesible=T|IndexInSheet=20|OwnerPartId=1|LineWidth=1|Color=16711680|LocationCount=7|X1=250|Y1=420|X2=247|Y2=423|X3=241|Y3=417|X4=235|Y4=423|X5=229|Y5=417|X6=223|Y6=423|X7=220|Y7=420
|RECORD=41|OwnerIndex=240|IndexInSheet=21|OwnerPartId=-1|Location.X=196|Location.X_Frac=61102|Location.Y=434|Color=8388608|FontID=1|IsHidden=T|Text=<VELENTIUM>|Name=VELENTIUM PART NUM
|RECORD=34|OwnerIndex=240|IndexInSheet=-1|OwnerPartId=-1|Location.X=219|Location.Y=424|Color=8388608|FontID=3|Text=R35|Name=Designator|ReadOnlyState=1
|RECORD=41|OwnerIndex=240|IndexInSheet=-1|OwnerPartId=-1|Location.X=230|Location.Y=410|Color=8388608|FontID=2|IsHidden=T|Text==MFG PART NUM|Name=Comment
|RECORD=44|OwnerIndex=240
|RECORD=45|OwnerIndex=267|IndexInSheet=-1|Description=Chip Resistor, 0603, 2-Leads, Body 1.57x0.85mm, IPC Medium Density|UseComponentLibrary=T|ModelName=RESC1608X50N|ModelType=PCBLIB|DatafileCount=1|ModelDatafileEntity0=RESC1608X50N|ModelDatafileKind0=PCBLib|IsCurrent=T|DatalinksLocked=T|DatabaseDatalinksLocked=T|IntegratedModel=T|DatabaseModel=T
|RECORD=46|OwnerIndex=268
|RECORD=48|OwnerIndex=268
|RECORD=1|LibReference=RES_0603_10K|ComponentDescription=RES, 10K, 1%, 1/10W, TF, 0603|PartCount=2|DisplayModeCount=1|IndexInSheet=48|OwnerPartId=-1|Location.X=580|Location.Y=430|Orientation=1|CurrentPartId=1|LibraryPath=*|SourceLibraryName=Resistors.IntLib|TargetFileName=*|AreaColor=11599871|Color=128|PartIDLocked=F|DesignItemId=RES_0603_10K|AllPinCount=2
|RECORD=41|OwnerIndex=271|OwnerPartId=-1|Location.X=576|Location.Y=482|Color=8388608|FontID=2|IsHidden=T|Text=7/25/2013|Name=ModifyDate
|RECORD=41|OwnerIndex=271|IndexInSheet=1|OwnerPartId=-1|Location.X=576|Location.Y=482|Color=8388608|FontID=2|IsHidden=T|Text=ERJ-3EKF1002V|Name=MFG PART NUM
|RECORD=41|OwnerIndex=271|IndexInSheet=2|OwnerPartId=-1|Location.X=576|Location.Y=482|Color=8388608|FontID=2|IsHidden=T|Text=PANASONIC|Name=MFG NAME
|RECORD=41|OwnerIndex=271|IndexInSheet=3|OwnerPartId=-1|Location.X=576|Location.Y=482|Color=8388608|FontID=2|IsHidden=T|Text=RES|Name=CATEGORY
|RECORD=41|OwnerIndex=271|IndexInSheet=4|OwnerPartId=-1|Location.X=576|Location.Y=482|Color=8388608|FontID=2|IsHidden=T|Text=7/26/2013|Name=Date
|RECORD=41|OwnerIndex=271|IndexInSheet=5|OwnerPartId=-1|Location.X=576|Location.Y=482|Color=8388608|FontID=2|IsHidden=T|Text=1%|Name=P1
|RECORD=41|OwnerIndex=271|IndexInSheet=6|OwnerPartId=-1|Location.X=576|Location.Y=482|Color=8388608|FontID=2|IsHidden=T|Text=TF|Name=P3
|RECORD=41|OwnerIndex=271|IndexInSheet=7|OwnerPartId=-1|Location.X=576|Location.Y=482|Color=8388608|FontID=2|IsHidden=T|Text=1/10W|Name=P2
|RECORD=41|OwnerIndex=271|IndexInSheet=8|OwnerPartId=-1|Location.X=576|Location.Y=482|Color=8388608|FontID=2|IsHidden=T|Text=125C|Name=MAXTEMP
|RECORD=41|OwnerIndex=271|IndexInSheet=9|OwnerPartId=-1|Location.X=576|Location.Y=482|Color=8388608|FontID=2|IsHidden=T|Text=-55C|Name=MINTEMP
|RECORD=41|OwnerIndex=271|IndexInSheet=10|OwnerPartId=-1|Location.X=576|Location.Y=482|Color=8388608|FontID=2|IsHidden=T|Text=100PPM|Name=OTHER
|RECORD=41|OwnerIndex=271|IndexInSheet=11|OwnerPartId=-1|Location.X=576|Location.Y=482|Color=8388608|FontID=2|IsHidden=T|Text=0603|Name=SIZE
|RECORD=41|OwnerIndex=271|IndexInSheet=12|OwnerPartId=-1|Location.X=576|Location.Y=482|Color=8388608|FontID=2|IsHidden=T|Text=GENERIC|Name=SUB
|RECORD=41|OwnerIndex=271|IndexInSheet=13|OwnerPartId=-1|Location.X=576|Location.Y=482|Color=8388608|FontID=2|IsHidden=T|Text=Digi-Key|Name=Supplier 1|ReadOnlyState=3
|RECORD=41|OwnerIndex=271|IndexInSheet=14|OwnerPartId=-1|Location.X=576|Location.Y=482|Color=8388608|FontID=2|IsHidden=T|Text=P10.0KHCT-ND|Name=Supplier Part Number 1|ReadOnlyState=3
|RECORD=41|OwnerIndex=271|IndexInSheet=15|OwnerPartId=-1|Location.X=576|Location.Y=482|Color=8388608|FontID=1|IsHidden=T|Text=*|Name=SHEETPART
|RECORD=41|OwnerIndex=271|IndexInSheet=16|OwnerPartId=-1|Location.X=576|Location.Y=482|Color=8388608|FontID=1|IsHidden=T|Text=RES, 10K, 1%, 1/10W, TF, 0603|Name=DESC
|RECORD=41|OwnerIndex=271|IndexInSheet=17|OwnerPartId=-1|Location.X=584|Location.Y=445|Color=8388608|FontID=2|Text=10K|Name=VALUE
|RECORD=2|OwnerIndex=271|OwnerPartId=1|FormalType=1|Electrical=4|PinConglomerate=35|PinLength=10|Location.X=580|Location.Y=440|Name=1|Designator=1|PinPropagationDelay=0.000000E+000
|RECORD=2|OwnerIndex=271|OwnerPartId=1|FormalType=1|Electrical=4|PinConglomerate=33|PinLength=10|Location.X=580|Location.Y=470|Name=2|Designator=2|PinPropagationDelay=0.000000E+000
|RECORD=6|OwnerIndex=271|IsNotAccesible=T|IndexInSheet=20|OwnerPartId=1|LineWidth=1|Color=16711680|LocationCount=7|X1=580|Y1=470|X2=577|Y2=467|X3=583|Y3=461|X4=577|Y4=455|X5=583|Y5=449|X6=577|Y6=443|X7=580|Y7=440
|RECORD=41|OwnerIndex=271|IndexInSheet=21|OwnerPartId=-1|Location.X=576|Location.Y=482|Color=8388608|FontID=1|IsHidden=T|Text=<VELENTIUM>|Name=VELENTIUM PART NUM
|RECORD=34|OwnerIndex=271|IndexInSheet=-1|OwnerPartId=-1|Location.X=584|Location.Y=457|Color=8388608|FontID=3|Text=R34|Name=Designator|ReadOnlyState=1
|RECORD=41|OwnerIndex=271|IndexInSheet=-1|OwnerPartId=-1|Location.X=576|Location.Y=482|Color=8388608|FontID=2|IsHidden=T|Text==MFG PART NUM|Name=Comment
|RECORD=44|OwnerIndex=271
|RECORD=45|OwnerIndex=298|IndexInSheet=-1|Description=Chip Resistor, 0603, 2-Leads, Body 1.57x0.85mm, IPC Medium Density|UseComponentLibrary=T|ModelName=RESC1608X50N|ModelType=PCBLIB|DatafileCount=1|ModelDatafileEntity0=RESC1608X50N|ModelDatafileKind0=PCBLib|IsCurrent=T|DatalinksLocked=T|DatabaseDatalinksLocked=T|IntegratedModel=T|DatabaseModel=T
|RECORD=46|OwnerIndex=299
|RECORD=48|OwnerIndex=299
|RECORD=1|LibReference=RES_0603_10K|ComponentDescription=RES, 10K, 1%, 1/10W, TF, 0603|PartCount=2|DisplayModeCount=1|IndexInSheet=49|OwnerPartId=-1|Location.X=270|Location.Y=430|Orientation=1|CurrentPartId=1|LibraryPath=*|SourceLibraryName=Resistors.IntLib|TargetFileName=*|AreaColor=11599871|Color=128|PartIDLocked=F|DesignItemId=RES_0603_10K|AllPinCount=2
|RECORD=41|OwnerIndex=302|OwnerPartId=-1|Location.X=266|Location.Y=482|Color=8388608|FontID=2|IsHidden=T|Text=7/25/2013|Name=ModifyDate
|RECORD=41|OwnerIndex=302|IndexInSheet=1|OwnerPartId=-1|Location.X=266|Location.Y=482|Color=8388608|FontID=2|IsHidden=T|Text=ERJ-3EKF1002V|Name=MFG PART NUM
|RECORD=41|OwnerIndex=302|IndexInSheet=2|OwnerPartId=-1|Location.X=266|Location.Y=482|Color=8388608|FontID=2|IsHidden=T|Text=PANASONIC|Name=MFG NAME
|RECORD=41|OwnerIndex=302|IndexInSheet=3|OwnerPartId=-1|Location.X=266|Location.Y=482|Color=8388608|FontID=2|IsHidden=T|Text=RES|Name=CATEGORY
|RECORD=41|OwnerIndex=302|IndexInSheet=4|OwnerPartId=-1|Location.X=266|Location.Y=482|Color=8388608|FontID=2|IsHidden=T|Text=7/26/2013|Name=Date
|RECORD=41|OwnerIndex=302|IndexInSheet=5|OwnerPartId=-1|Location.X=266|Location.Y=482|Color=8388608|FontID=2|IsHidden=T|Text=1%|Name=P1
|RECORD=41|OwnerIndex=302|IndexInSheet=6|OwnerPartId=-1|Location.X=266|Location.Y=482|Color=8388608|FontID=2|IsHidden=T|Text=TF|Name=P3
|RECORD=41|OwnerIndex=302|IndexInSheet=7|OwnerPartId=-1|Location.X=266|Location.Y=482|Color=8388608|FontID=2|IsHidden=T|Text=1/10W|Name=P2
|RECORD=41|OwnerIndex=302|IndexInSheet=8|OwnerPartId=-1|Location.X=266|Location.Y=482|Color=8388608|FontID=2|IsHidden=T|Text=125C|Name=MAXTEMP
|RECORD=41|OwnerIndex=302|IndexInSheet=9|OwnerPartId=-1|Location.X=266|Location.Y=482|Color=8388608|FontID=2|IsHidden=T|Text=-55C|Name=MINTEMP
|RECORD=41|OwnerIndex=302|IndexInSheet=10|OwnerPartId=-1|Location.X=266|Location.Y=482|Color=8388608|FontID=2|IsHidden=T|Text=100PPM|Name=OTHER
|RECORD=41|OwnerIndex=302|IndexInSheet=11|OwnerPartId=-1|Location.X=266|Location.Y=482|Color=8388608|FontID=2|IsHidden=T|Text=0603|Name=SIZE
|RECORD=41|OwnerIndex=302|IndexInSheet=12|OwnerPartId=-1|Location.X=266|Location.Y=482|Color=8388608|FontID=2|IsHidden=T|Text=GENERIC|Name=SUB
|RECORD=41|OwnerIndex=302|IndexInSheet=13|OwnerPartId=-1|Location.X=266|Location.Y=482|Color=8388608|FontID=2|IsHidden=T|Text=Digi-Key|Name=Supplier 1|ReadOnlyState=3
|RECORD=41|OwnerIndex=302|IndexInSheet=14|OwnerPartId=-1|Location.X=266|Location.Y=482|Color=8388608|FontID=2|IsHidden=T|Text=P10.0KHCT-ND|Name=Supplier Part Number 1|ReadOnlyState=3
|RECORD=41|OwnerIndex=302|IndexInSheet=15|OwnerPartId=-1|Location.X=266|Location.Y=482|Color=8388608|FontID=1|IsHidden=T|Text=*|Name=SHEETPART
|RECORD=41|OwnerIndex=302|IndexInSheet=16|OwnerPartId=-1|Location.X=266|Location.Y=482|Color=8388608|FontID=1|IsHidden=T|Text=RES, 10K, 1%, 1/10W, TF, 0603|Name=DESC
|RECORD=41|OwnerIndex=302|IndexInSheet=17|OwnerPartId=-1|Location.X=274|Location.Y=445|Color=8388608|FontID=2|Text=10K|Name=VALUE
|RECORD=2|OwnerIndex=302|OwnerPartId=1|FormalType=1|Electrical=4|PinConglomerate=35|PinLength=10|Location.X=270|Location.Y=440|Name=1|Designator=1|PinPropagationDelay=0.000000E+000
|RECORD=2|OwnerIndex=302|OwnerPartId=1|FormalType=1|Electrical=4|PinConglomerate=33|PinLength=10|Location.X=270|Location.Y=470|Name=2|Designator=2|PinPropagationDelay=0.000000E+000
|RECORD=6|OwnerIndex=302|IsNotAccesible=T|IndexInSheet=20|OwnerPartId=1|LineWidth=1|Color=16711680|LocationCount=7|X1=270|Y1=470|X2=267|Y2=467|X3=273|Y3=461|X4=267|Y4=455|X5=273|Y5=449|X6=267|Y6=443|X7=270|Y7=440
|RECORD=41|OwnerIndex=302|IndexInSheet=21|OwnerPartId=-1|Location.X=266|Location.Y=482|Color=8388608|FontID=1|IsHidden=T|Text=<VELENTIUM>|Name=VELENTIUM PART NUM
|RECORD=34|OwnerIndex=302|IndexInSheet=-1|OwnerPartId=-1|Location.X=274|Location.Y=457|Color=8388608|FontID=3|Text=R33|Name=Designator|ReadOnlyState=1
|RECORD=41|OwnerIndex=302|IndexInSheet=-1|OwnerPartId=-1|Location.X=266|Location.Y=482|Color=8388608|FontID=2|IsHidden=T|Text==MFG PART NUM|Name=Comment
|RECORD=44|OwnerIndex=302
|RECORD=45|OwnerIndex=329|IndexInSheet=-1|Description=Chip Resistor, 0603, 2-Leads, Body 1.57x0.85mm, IPC Medium Density|UseComponentLibrary=T|ModelName=RESC1608X50N|ModelType=PCBLIB|DatafileCount=1|ModelDatafileEntity0=RESC1608X50N|ModelDatafileKind0=PCBLib|IsCurrent=T|DatalinksLocked=T|DatabaseDatalinksLocked=T|IntegratedModel=T|DatabaseModel=T
|RECORD=46|OwnerIndex=330
|RECORD=48|OwnerIndex=330
|RECORD=1|LibReference=B3U-1000P|ComponentDescription=SW, SPST-NO, TACT, 12V, 50MA, 3X2.5MM SMT, B3U SERIES|PartCount=2|DisplayModeCount=1|IndexInSheet=50|OwnerPartId=-1|Location.X=300|Location.Y=420|CurrentPartId=1|LibraryPath=*|SourceLibraryName=Miscellaneous.IntLib|TargetFileName=*|AreaColor=11599871|Color=128|PartIDLocked=F|DesignItemId=B3U-1000P|AllPinCount=2
|RECORD=41|OwnerIndex=333|OwnerPartId=-1|Location.X=300|Location.Y=420|Color=8388608|FontID=2|IsHidden=T|Text=B3U-1000P|Name=MFG PART NUM
|RECORD=41|OwnerIndex=333|IndexInSheet=1|OwnerPartId=-1|Location.X=300|Location.Y=420|Color=8388608|FontID=2|IsHidden=T|Text=9/5/2013|Name=MODIFY DATE
|RECORD=41|OwnerIndex=333|IndexInSheet=2|OwnerPartId=-1|Location.X=300|Location.Y=420|Color=8388608|FontID=2|IsHidden=T|Text=OMRON|Name=MFG NAME
|RECORD=41|OwnerIndex=333|IndexInSheet=3|OwnerPartId=-1|Location.X=298|Location.Y=457|Location.Y_Frac=10000|Color=8388608|FontID=2|IsHidden=T|Name=Date
|RECORD=41|OwnerIndex=333|IndexInSheet=4|OwnerPartId=-1|Location.X=298|Location.Y=457|Location.Y_Frac=10000|Color=8388608|FontID=2|IsHidden=T|Text=SW|Name=CATEGORY
|RECORD=41|OwnerIndex=333|IndexInSheet=5|OwnerPartId=-1|Location.X=298|Location.Y=457|Location.Y_Frac=10000|Color=8388608|FontID=2|IsHidden=T|Text=70C|Name=MAXTEMP
|RECORD=41|OwnerIndex=333|IndexInSheet=6|OwnerPartId=-1|Location.X=298|Location.Y=457|Location.Y_Frac=10000|Color=8388608|FontID=2|IsHidden=T|Text=-25C|Name=MINTEMP
|RECORD=41|OwnerIndex=333|IndexInSheet=7|OwnerPartId=-1|Location.X=298|Location.Y=457|Location.Y_Frac=10000|Color=8388608|FontID=2|IsHidden=T|Text=B3U SERIES|Name=OTHER
|RECORD=41|OwnerIndex=333|IndexInSheet=8|OwnerPartId=-1|Location.X=298|Location.Y=457|Location.Y_Frac=10000|Color=8388608|FontID=2|IsHidden=T|Text=12V|Name=P1
|RECORD=41|OwnerIndex=333|IndexInSheet=9|OwnerPartId=-1|Location.X=298|Location.Y=457|Location.Y_Frac=10000|Color=8388608|FontID=2|IsHidden=T|Text=50mA|Name=P2
|RECORD=41|OwnerIndex=333|IndexInSheet=10|OwnerPartId=-1|Location.X=298|Location.Y=457|Location.Y_Frac=10000|Color=8388608|FontID=2|IsHidden=T|Text=TACT|Name=P3
|RECORD=41|OwnerIndex=333|IndexInSheet=11|OwnerPartId=-1|Location.X=298|Location.Y=457|Location.Y_Frac=10000|Color=8388608|FontID=2|IsHidden=T|Text=3X2.5MM|Name=SIZE
|RECORD=41|OwnerIndex=333|IndexInSheet=12|OwnerPartId=-1|Location.X=298|Location.Y=457|Location.Y_Frac=10000|Color=8388608|FontID=2|IsHidden=T|Name=SUB
|RECORD=41|OwnerIndex=333|IndexInSheet=13|OwnerPartId=-1|Location.X=298|Location.Y=407|Color=8388608|FontID=1|IsHidden=T|Text=*|Name=SHEETPART
|RECORD=41|OwnerIndex=333|IndexInSheet=14|OwnerPartId=-1|Location.X=298|Location.Y=461|Location.Y_Frac=10000|Color=8388608|FontID=1|IsHidden=T|Text=SW, SPST-NO, TACT, 12V, 50MA, 3X2.5MM SMT, B3U SERIES|Name=DESC
|RECORD=41|OwnerIndex=333|IndexInSheet=15|OwnerPartId=-1|Location.X=298|Location.Y=461|Location.Y_Frac=10000|Color=8388608|FontID=1|IsHidden=T|Text=Digi-Key|Name=Supplier 1|ReadOnlyState=3
|RECORD=41|OwnerIndex=333|IndexInSheet=16|OwnerPartId=-1|Location.X=298|Location.Y=461|Location.Y_Frac=10000|Color=8388608|FontID=1|IsHidden=T|Text=SW1020CT-ND|Name=Supplier Part Number 1|ReadOnlyState=3
|RECORD=41|OwnerIndex=333|IndexInSheet=17|OwnerPartId=-1|Location.X=325|Location.Y=405|Color=8388608|FontID=2|Text=SPST-NO|Name=VALUE
|RECORD=2|OwnerIndex=333|OwnerPartId=1|FormalType=1|Electrical=4|PinConglomerate=48|PinLength=25|Location.X=365|Location.Y=420|Designator=1|PinPropagationDelay=0.000000E+000
|RECORD=2|OwnerIndex=333|OwnerPartId=1|FormalType=1|Electrical=4|PinConglomerate=50|PinLength=25|Location.X=325|Location.Y=420|Designator=2|PinPropagationDelay=0.000000E+000
|RECORD=12|OwnerIndex=333|IsNotAccesible=T|IndexInSheet=20|OwnerPartId=1|Location.X=345|Location.Y=417|Location.Y_Frac=50000|Radius=26|Radius_Frac=90002|LineWidth=1|StartAngle=68.000|EndAngle=112.000|Color=16711680
|RECORD=12|OwnerIndex=333|IsNotAccesible=T|IndexInSheet=21|OwnerPartId=1|Location.X=362|Location.X_Frac=50000|Location.Y=420|Radius=2|Radius_Frac=50000|LineWidth=1|EndAngle=360.000|Color=16711680
|RECORD=12|OwnerIndex=333|IsNotAccesible=T|IndexInSheet=22|OwnerPartId=1|Location.X=327|Location.X_Frac=50000|Location.Y=420|Radius=2|Radius_Frac=50000|LineWidth=1|EndAngle=360.000|Color=16711680
|RECORD=13|OwnerIndex=333|IsNotAccesible=T|IndexInSheet=23|OwnerPartId=1|Location.X=345|Location.Y=444|Corner.X=345|Corner.Y=430|LineWidth=1|Color=16711680
|RECORD=13|OwnerIndex=333|IsNotAccesible=T|IndexInSheet=24|OwnerPartId=1|Location.X=362|Location.X_Frac=50000|Location.Y=430|Corner.X=327|Corner.X_Frac=50000|Corner.Y=430|LineWidth=1|Color=16711680
|RECORD=41|OwnerIndex=333|IndexInSheet=25|OwnerPartId=-1|Location.X=298|Location.Y=461|Location.Y_Frac=10000|Color=8388608|FontID=1|IsHidden=T|Text=<VALENTIUM>|Name=VALENTIUM PART NUM
|RECORD=34|OwnerIndex=333|IndexInSheet=-1|OwnerPartId=-1|Location.X=325|Location.Y=445|Color=8388608|FontID=3|Text=S5|Name=Designator|ReadOnlyState=1
|RECORD=41|OwnerIndex=333|IndexInSheet=-1|OwnerPartId=-1|Location.X=340|Location.Y=410|Color=8388608|FontID=2|IsHidden=T|Text=B3U-1000P|Name=Comment
|RECORD=44|OwnerIndex=333
|RECORD=45|OwnerIndex=364|IndexInSheet=-1|Description=SW, SPST-NO TACT 2.5X3MM|UseComponentLibrary=T|ModelName=OMRON-B3U-1000P|ModelType=PCBLIB|DatafileCount=1|ModelDatafileEntity0=OMRON-B3U-1000P|ModelDatafileKind0=PCBLib|IsCurrent=T|DatalinksLocked=T|DatabaseDatalinksLocked=T|IntegratedModel=T|DatabaseModel=T
|RECORD=46|OwnerIndex=365
|RECORD=48|OwnerIndex=365
|RECORD=1|LibReference=B3U-1000P|ComponentDescription=SW, SPST-NO, TACT, 12V, 50MA, 3X2.5MM SMT, B3U SERIES|PartCount=2|DisplayModeCount=1|IndexInSheet=51|OwnerPartId=-1|Location.X=610|Location.Y=420|CurrentPartId=1|LibraryPath=*|SourceLibraryName=Miscellaneous.IntLib|TargetFileName=*|AreaColor=11599871|Color=128|PartIDLocked=F|DesignItemId=B3U-1000P|AllPinCount=2
|RECORD=41|OwnerIndex=368|OwnerPartId=-1|Location.X=610|Location.Y=420|Color=8388608|FontID=2|IsHidden=T|Text=B3U-1000P|Name=MFG PART NUM
|RECORD=41|OwnerIndex=368|IndexInSheet=1|OwnerPartId=-1|Location.X=610|Location.Y=420|Color=8388608|FontID=2|IsHidden=T|Text=9/5/2013|Name=MODIFY DATE
|RECORD=41|OwnerIndex=368|IndexInSheet=2|OwnerPartId=-1|Location.X=610|Location.Y=420|Color=8388608|FontID=2|IsHidden=T|Text=OMRON|Name=MFG NAME
|RECORD=41|OwnerIndex=368|IndexInSheet=3|OwnerPartId=-1|Location.X=608|Location.Y=457|Location.Y_Frac=10000|Color=8388608|FontID=2|IsHidden=T|Name=Date
|RECORD=41|OwnerIndex=368|IndexInSheet=4|OwnerPartId=-1|Location.X=608|Location.Y=457|Location.Y_Frac=10000|Color=8388608|FontID=2|IsHidden=T|Text=SW|Name=CATEGORY
|RECORD=41|OwnerIndex=368|IndexInSheet=5|OwnerPartId=-1|Location.X=608|Location.Y=457|Location.Y_Frac=10000|Color=8388608|FontID=2|IsHidden=T|Text=70C|Name=MAXTEMP
|RECORD=41|OwnerIndex=368|IndexInSheet=6|OwnerPartId=-1|Location.X=608|Location.Y=457|Location.Y_Frac=10000|Color=8388608|FontID=2|IsHidden=T|Text=-25C|Name=MINTEMP
|RECORD=41|OwnerIndex=368|IndexInSheet=7|OwnerPartId=-1|Location.X=608|Location.Y=457|Location.Y_Frac=10000|Color=8388608|FontID=2|IsHidden=T|Text=B3U SERIES|Name=OTHER
|RECORD=41|OwnerIndex=368|IndexInSheet=8|OwnerPartId=-1|Location.X=608|Location.Y=457|Location.Y_Frac=10000|Color=8388608|FontID=2|IsHidden=T|Text=12V|Name=P1
|RECORD=41|OwnerIndex=368|IndexInSheet=9|OwnerPartId=-1|Location.X=608|Location.Y=457|Location.Y_Frac=10000|Color=8388608|FontID=2|IsHidden=T|Text=50mA|Name=P2
|RECORD=41|OwnerIndex=368|IndexInSheet=10|OwnerPartId=-1|Location.X=608|Location.Y=457|Location.Y_Frac=10000|Color=8388608|FontID=2|IsHidden=T|Text=TACT|Name=P3
|RECORD=41|OwnerIndex=368|IndexInSheet=11|OwnerPartId=-1|Location.X=608|Location.Y=457|Location.Y_Frac=10000|Color=8388608|FontID=2|IsHidden=T|Text=3X2.5MM|Name=SIZE
|RECORD=41|OwnerIndex=368|IndexInSheet=12|OwnerPartId=-1|Location.X=608|Location.Y=457|Location.Y_Frac=10000|Color=8388608|FontID=2|IsHidden=T|Name=SUB
|RECORD=41|OwnerIndex=368|IndexInSheet=13|OwnerPartId=-1|Location.X=608|Location.Y=407|Color=8388608|FontID=1|IsHidden=T|Text=*|Name=SHEETPART
|RECORD=41|OwnerIndex=368|IndexInSheet=14|OwnerPartId=-1|Location.X=608|Location.Y=461|Location.Y_Frac=10000|Color=8388608|FontID=1|IsHidden=T|Text=SW, SPST-NO, TACT, 12V, 50MA, 3X2.5MM SMT, B3U SERIES|Name=DESC
|RECORD=41|OwnerIndex=368|IndexInSheet=15|OwnerPartId=-1|Location.X=608|Location.Y=461|Location.Y_Frac=10000|Color=8388608|FontID=1|IsHidden=T|Text=Digi-Key|Name=Supplier 1|ReadOnlyState=3
|RECORD=41|OwnerIndex=368|IndexInSheet=16|OwnerPartId=-1|Location.X=608|Location.Y=461|Location.Y_Frac=10000|Color=8388608|FontID=1|IsHidden=T|Text=SW1020CT-ND|Name=Supplier Part Number 1|ReadOnlyState=3
|RECORD=41|OwnerIndex=368|IndexInSheet=17|OwnerPartId=-1|Location.X=635|Location.Y=405|Color=8388608|FontID=2|Text=SPST-NO|Name=VALUE
|RECORD=2|OwnerIndex=368|OwnerPartId=1|FormalType=1|Electrical=4|PinConglomerate=48|PinLength=25|Location.X=675|Location.Y=420|Designator=1|PinPropagationDelay=0.000000E+000
|RECORD=2|OwnerIndex=368|OwnerPartId=1|FormalType=1|Electrical=4|PinConglomerate=50|PinLength=25|Location.X=635|Location.Y=420|Designator=2|PinPropagationDelay=0.000000E+000
|RECORD=12|OwnerIndex=368|IsNotAccesible=T|IndexInSheet=20|OwnerPartId=1|Location.X=655|Location.Y=417|Location.Y_Frac=50000|Radius=26|Radius_Frac=90002|LineWidth=1|StartAngle=68.000|EndAngle=112.000|Color=16711680
|RECORD=12|OwnerIndex=368|IsNotAccesible=T|IndexInSheet=21|OwnerPartId=1|Location.X=672|Location.X_Frac=50000|Location.Y=420|Radius=2|Radius_Frac=50000|LineWidth=1|EndAngle=360.000|Color=16711680
|RECORD=12|OwnerIndex=368|IsNotAccesible=T|IndexInSheet=22|OwnerPartId=1|Location.X=637|Location.X_Frac=50000|Location.Y=420|Radius=2|Radius_Frac=50000|LineWidth=1|EndAngle=360.000|Color=16711680
|RECORD=13|OwnerIndex=368|IsNotAccesible=T|IndexInSheet=23|OwnerPartId=1|Location.X=655|Location.Y=444|Corner.X=655|Corner.Y=430|LineWidth=1|Color=16711680
|RECORD=13|OwnerIndex=368|IsNotAccesible=T|IndexInSheet=24|OwnerPartId=1|Location.X=672|Location.X_Frac=50000|Location.Y=430|Corner.X=637|Corner.X_Frac=50000|Corner.Y=430|LineWidth=1|Color=16711680
|RECORD=41|OwnerIndex=368|IndexInSheet=25|OwnerPartId=-1|Location.X=608|Location.Y=461|Location.Y_Frac=10000|Color=8388608|FontID=1|IsHidden=T|Text=<VALENTIUM>|Name=VALENTIUM PART NUM
|RECORD=34|OwnerIndex=368|IndexInSheet=-1|OwnerPartId=-1|Location.X=635|Location.Y=445|Color=8388608|FontID=3|Text=S6|Name=Designator|ReadOnlyState=1
|RECORD=41|OwnerIndex=368|IndexInSheet=-1|OwnerPartId=-1|Location.X=650|Location.Y=410|Color=8388608|FontID=2|IsHidden=T|Text=B3U-1000P|Name=Comment
|RECORD=44|OwnerIndex=368
|RECORD=45|OwnerIndex=399|IndexInSheet=-1|Description=SW, SPST-NO TACT 2.5X3MM|UseComponentLibrary=T|ModelName=OMRON-B3U-1000P|ModelType=PCBLIB|DatafileCount=1|ModelDatafileEntity0=OMRON-B3U-1000P|ModelDatafileKind0=PCBLib|IsCurrent=T|DatalinksLocked=T|DatabaseDatalinksLocked=T|IntegratedModel=T|DatabaseModel=T
|RECORD=46|OwnerIndex=400
|RECORD=48|OwnerIndex=400
|RECORD=4|IndexInSheet=52|OwnerPartId=-1|Location.X=460|Location.Y=800|Color=8388608|FontID=4|Text=LEDS
|RECORD=4|IndexInSheet=53|OwnerPartId=-1|Location.X=440|Location.Y=510|Color=8388608|FontID=4|Text=BUTTONS
|RECORD=1|LibReference=SMCJ6.5CA|ComponentDescription=DIO, TVS, SMCJ6.5, 6.5V, BIDIR, 1.5KW, SMC|PartCount=2|DisplayModeCount=1|IndexInSheet=54|OwnerPartId=-1|Location.X=1370|Location.Y=590|Orientation=1|CurrentPartId=1|LibraryPath=*|SourceLibraryName=Passives.IntLib|TargetFileName=*|AreaColor=11599871|Color=128|PartIDLocked=F|DesignItemId=SMCJ6.5CA|AllPinCount=2
|RECORD=41|OwnerIndex=405|OwnerPartId=-1|Location.X=1363|Location.Y=662|Color=8388608|FontID=2|IsHidden=T|Text=SMCJ6.5CA|Name=MFG PART NUM
|RECORD=41|OwnerIndex=405|IndexInSheet=1|OwnerPartId=-1|Location.X=1363|Location.Y=662|Color=8388608|FontID=2|IsHidden=T|Text=9/4/2013|Name=MODIFY DATE
|RECORD=41|OwnerIndex=405|IndexInSheet=2|OwnerPartId=-1|Location.X=1363|Location.Y=662|Color=8388608|FontID=2|IsHidden=T|Text=LITTELFUSE|Name=MFG NAME
|RECORD=41|OwnerIndex=405|IndexInSheet=3|OwnerPartId=-1|Location.X=1363|Location.Y=662|Color=8388608|FontID=2|IsHidden=T|Text=DIO, TVS|Name=CATEGORY
|RECORD=41|OwnerIndex=405|IndexInSheet=4|OwnerPartId=-1|Location.X=1363|Location.Y=662|Color=8388608|FontID=2|IsHidden=T|Name=DATE
|RECORD=41|OwnerIndex=405|IndexInSheet=5|OwnerPartId=-1|Location.X=1363|Location.Y=662|Color=8388608|FontID=2|IsHidden=T|Text=150C|Name=MAXTEMP
|RECORD=41|OwnerIndex=405|IndexInSheet=6|OwnerPartId=-1|Location.X=1363|Location.Y=662|Color=8388608|FontID=2|IsHidden=T|Text=-55C|Name=MINTEMP
|RECORD=41|OwnerIndex=405|IndexInSheet=7|OwnerPartId=-1|Location.X=1363|Location.Y=662|Color=8388608|FontID=2|IsHidden=T|Text=SMCJ|Name=OTHER
|RECORD=41|OwnerIndex=405|IndexInSheet=8|OwnerPartId=-1|Location.X=1363|Location.Y=662|Color=8388608|FontID=2|IsHidden=T|Text=6.5V|Name=P1
|RECORD=41|OwnerIndex=405|IndexInSheet=9|OwnerPartId=-1|Location.X=1363|Location.Y=662|Color=8388608|FontID=2|IsHidden=T|Text=BIDIR|Name=P2
|RECORD=41|OwnerIndex=405|IndexInSheet=10|OwnerPartId=-1|Location.X=1363|Location.Y=662|Color=8388608|FontID=2|IsHidden=T|Text=1.5KW|Name=P3
|RECORD=41|OwnerIndex=405|IndexInSheet=11|OwnerPartId=-1|Location.X=1363|Location.Y=662|Color=8388608|FontID=2|IsHidden=T|Text=SMC|Name=SIZE
|RECORD=41|OwnerIndex=405|IndexInSheet=12|OwnerPartId=-1|Location.X=1363|Location.Y=662|Color=8388608|FontID=2|IsHidden=T|Name=SUB
|RECORD=41|OwnerIndex=405|IndexInSheet=13|OwnerPartId=-1|Location.X=1363|Location.Y=662|Color=8388608|FontID=1|IsHidden=T|Text=*|Name=SHEETPART
|RECORD=41|OwnerIndex=405|IndexInSheet=14|OwnerPartId=-1|Location.X=1363|Location.Y=662|Color=8388608|FontID=1|IsHidden=T|Text=Digi-Key|Name=Supplier 1|ReadOnlyState=3
|RECORD=41|OwnerIndex=405|IndexInSheet=15|OwnerPartId=-1|Location.X=1363|Location.Y=662|Color=8388608|FontID=1|IsHidden=T|Text=SMCJ6.5CALFCT-ND|Name=Supplier Part Number 1|ReadOnlyState=3
|RECORD=41|OwnerIndex=405|IndexInSheet=16|OwnerPartId=-1|Location.X=1363|Location.Y=662|Color=8388608|FontID=1|IsHidden=T|Text=DIO, TVS, SMCJ6.5, 6.5V, BIDIR, 1.5KW, SMC|Name=DESC
|RECORD=41|OwnerIndex=405|IndexInSheet=17|OwnerPartId=-1|Location.X=1377|Location.Y=615|Color=8388608|FontID=2|Text=SMCJ6.5|Name=VALUE
|RECORD=2|OwnerIndex=405|OwnerPartId=1|FormalType=1|Electrical=4|PinConglomerate=35|PinLength=20|Location.X=1370|Location.Y=610|Name=K|Designator=K|SwapIdPin=2|SwapIDPart=1|PinPropagationDelay=0.000000E+000
|RECORD=2|OwnerIndex=405|OwnerPartId=1|FormalType=1|Electrical=4|PinConglomerate=33|PinLength=20|Location.X=1370|Location.Y=640|Name=A|Designator=A|SwapIdPin=1|SwapIDPart=1|PinPropagationDelay=0.000000E+000
|RECORD=13|OwnerIndex=405|IsNotAccesible=T|IndexInSheet=20|OwnerPartId=1|Location.X=1370|Location.Y=620|Corner.X=1370|Corner.Y=630|LineWidth=1|Color=16711680
|RECORD=13|OwnerIndex=405|IsNotAccesible=T|IndexInSheet=21|OwnerPartId=1|Location.X=1370|Location.Y=610|Corner.X=1370|Corner.Y=620|LineWidth=1|Color=16711680
|RECORD=13|OwnerIndex=405|IsNotAccesible=T|IndexInSheet=22|OwnerPartId=1|Location.X=1370|Location.Y=640|Corner.X=1370|Corner.Y=630|LineWidth=1|Color=16711680
|RECORD=7|OwnerIndex=405|IsNotAccesible=T|IndexInSheet=23|OwnerPartId=1|LineWidth=1|Color=16711680|AreaColor=16711680|IsSolid=T|LocationCount=3|X1=1370|Y1=616|X2=1376|Y2=623|X3=1364|Y3=623
|RECORD=13|OwnerIndex=405|IsNotAccesible=T|IndexInSheet=24|OwnerPartId=1|Location.X=1364|Location.Y=614|Corner.X=1366|Corner.Y=616|LineWidth=1|Color=16711680
|RECORD=13|OwnerIndex=405|IsNotAccesible=T|IndexInSheet=25|OwnerPartId=1|Location.X=1376|Location.Y=618|Corner.X=1374|Corner.Y=616|LineWidth=1|Color=16711680
|RECORD=13|OwnerIndex=405|IsNotAccesible=T|IndexInSheet=26|OwnerPartId=1|Location.X=1374|Location.Y=616|Corner.X=1366|Corner.Y=616|LineWidth=1|Color=16711680
|RECORD=7|OwnerIndex=405|IsNotAccesible=T|IndexInSheet=27|OwnerPartId=1|LineWidth=1|Color=16711680|AreaColor=16711680|IsSolid=T|LocationCount=3|X1=1370|Y1=634|X2=1364|Y2=627|X3=1376|Y3=627
|RECORD=13|OwnerIndex=405|IsNotAccesible=T|IndexInSheet=28|OwnerPartId=1|Location.X=1364|Location.Y=632|Corner.X=1366|Corner.Y=634|LineWidth=1|Color=16711680
|RECORD=13|OwnerIndex=405|IsNotAccesible=T|IndexInSheet=29|OwnerPartId=1|Location.X=1376|Location.Y=636|Corner.X=1374|Corner.Y=634|LineWidth=1|Color=16711680
|RECORD=13|OwnerIndex=405|IsNotAccesible=T|IndexInSheet=30|OwnerPartId=1|Location.X=1366|Location.Y=634|Corner.X=1374|Corner.Y=634|LineWidth=1|Color=16711680
|RECORD=41|OwnerIndex=405|IndexInSheet=31|OwnerPartId=-1|Location.X=1363|Location.Y=662|Color=8388608|FontID=1|IsHidden=T|Text=<VALENTIUM>|Name=VALENTIUM PART NUM
|RECORD=34|OwnerIndex=405|IndexInSheet=-1|OwnerPartId=-1|Location.X=1377|Location.Y=627|Color=8388608|FontID=3|Text=D15|Name=Designator|ReadOnlyState=1
|RECORD=41|OwnerIndex=405|IndexInSheet=-1|OwnerPartId=-1|Location.X=1363|Location.Y=662|Color=8388608|FontID=2|IsHidden=T|Text=SMCJ6.5CA|Name=Comment
|RECORD=44|OwnerIndex=405
|RECORD=45|OwnerIndex=442|IndexInSheet=-1|Description=Molded Diode, SMC, 2-Leads, Body 6.85x5.90mm, IPC Medium Density|UseComponentLibrary=T|ModelName=DIOM6959X26N|ModelType=PCBLIB|DatafileCount=1|ModelDatafileEntity0=DIOM6959X26N|ModelDatafileKind0=PCBLib|IsCurrent=T|DatalinksLocked=T|DatabaseDatalinksLocked=T|IntegratedModel=T|DatabaseModel=T
|RECORD=46|OwnerIndex=443
|RECORD=48|OwnerIndex=443
|RECORD=1|LibReference=SMCJ6.5CA|ComponentDescription=DIO, TVS, SMCJ6.5, 6.5V, BIDIR, 1.5KW, SMC|PartCount=2|DisplayModeCount=1|IndexInSheet=55|OwnerPartId=-1|Location.X=1090|Location.Y=320|Orientation=1|CurrentPartId=1|LibraryPath=*|SourceLibraryName=Passives.IntLib|TargetFileName=*|AreaColor=11599871|Color=128|PartIDLocked=F|DesignItemId=SMCJ6.5CA|AllPinCount=2
|RECORD=41|OwnerIndex=446|OwnerPartId=-1|Location.X=1083|Location.Y=392|Color=8388608|FontID=2|IsHidden=T|Text=SMCJ6.5CA|Name=MFG PART NUM
|RECORD=41|OwnerIndex=446|IndexInSheet=1|OwnerPartId=-1|Location.X=1083|Location.Y=392|Color=8388608|FontID=2|IsHidden=T|Text=9/4/2013|Name=MODIFY DATE
|RECORD=41|OwnerIndex=446|IndexInSheet=2|OwnerPartId=-1|Location.X=1083|Location.Y=392|Color=8388608|FontID=2|IsHidden=T|Text=LITTELFUSE|Name=MFG NAME
|RECORD=41|OwnerIndex=446|IndexInSheet=3|OwnerPartId=-1|Location.X=1083|Location.Y=392|Color=8388608|FontID=2|IsHidden=T|Text=DIO, TVS|Name=CATEGORY
|RECORD=41|OwnerIndex=446|IndexInSheet=4|OwnerPartId=-1|Location.X=1083|Location.Y=392|Color=8388608|FontID=2|IsHidden=T|Name=DATE
|RECORD=41|OwnerIndex=446|IndexInSheet=5|OwnerPartId=-1|Location.X=1083|Location.Y=392|Color=8388608|FontID=2|IsHidden=T|Text=150C|Name=MAXTEMP
|RECORD=41|OwnerIndex=446|IndexInSheet=6|OwnerPartId=-1|Location.X=1083|Location.Y=392|Color=8388608|FontID=2|IsHidden=T|Text=-55C|Name=MINTEMP
|RECORD=41|OwnerIndex=446|IndexInSheet=7|OwnerPartId=-1|Location.X=1083|Location.Y=392|Color=8388608|FontID=2|IsHidden=T|Text=SMCJ|Name=OTHER
|RECORD=41|OwnerIndex=446|IndexInSheet=8|OwnerPartId=-1|Location.X=1083|Location.Y=392|Color=8388608|FontID=2|IsHidden=T|Text=6.5V|Name=P1
|RECORD=41|OwnerIndex=446|IndexInSheet=9|OwnerPartId=-1|Location.X=1083|Location.Y=392|Color=8388608|FontID=2|IsHidden=T|Text=BIDIR|Name=P2
|RECORD=41|OwnerIndex=446|IndexInSheet=10|OwnerPartId=-1|Location.X=1083|Location.Y=392|Color=8388608|FontID=2|IsHidden=T|Text=1.5KW|Name=P3
|RECORD=41|OwnerIndex=446|IndexInSheet=11|OwnerPartId=-1|Location.X=1083|Location.Y=392|Color=8388608|FontID=2|IsHidden=T|Text=SMC|Name=SIZE
|RECORD=41|OwnerIndex=446|IndexInSheet=12|OwnerPartId=-1|Location.X=1083|Location.Y=392|Color=8388608|FontID=2|IsHidden=T|Name=SUB
|RECORD=41|OwnerIndex=446|IndexInSheet=13|OwnerPartId=-1|Location.X=1083|Location.Y=392|Color=8388608|FontID=1|IsHidden=T|Text=*|Name=SHEETPART
|RECORD=41|OwnerIndex=446|IndexInSheet=14|OwnerPartId=-1|Location.X=1083|Location.Y=392|Color=8388608|FontID=1|IsHidden=T|Text=Digi-Key|Name=Supplier 1|ReadOnlyState=3
|RECORD=41|OwnerIndex=446|IndexInSheet=15|OwnerPartId=-1|Location.X=1083|Location.Y=392|Color=8388608|FontID=1|IsHidden=T|Text=SMCJ6.5CALFCT-ND|Name=Supplier Part Number 1|ReadOnlyState=3
|RECORD=41|OwnerIndex=446|IndexInSheet=16|OwnerPartId=-1|Location.X=1083|Location.Y=392|Color=8388608|FontID=1|IsHidden=T|Text=DIO, TVS, SMCJ6.5, 6.5V, BIDIR, 1.5KW, SMC|Name=DESC
|RECORD=41|OwnerIndex=446|IndexInSheet=17|OwnerPartId=-1|Location.X=1097|Location.Y=345|Color=8388608|FontID=2|Text=SMCJ6.5|Name=VALUE
|RECORD=2|OwnerIndex=446|OwnerPartId=1|FormalType=1|Electrical=4|PinConglomerate=35|PinLength=20|Location.X=1090|Location.Y=340|Name=K|Designator=K|SwapIdPin=2|SwapIDPart=1|PinPropagationDelay=0.000000E+000
|RECORD=2|OwnerIndex=446|OwnerPartId=1|FormalType=1|Electrical=4|PinConglomerate=33|PinLength=20|Location.X=1090|Location.Y=370|Name=A|Designator=A|SwapIdPin=1|SwapIDPart=1|PinPropagationDelay=0.000000E+000
|RECORD=13|OwnerIndex=446|IsNotAccesible=T|IndexInSheet=20|OwnerPartId=1|Location.X=1090|Location.Y=350|Corner.X=1090|Corner.Y=360|LineWidth=1|Color=16711680
|RECORD=13|OwnerIndex=446|IsNotAccesible=T|IndexInSheet=21|OwnerPartId=1|Location.X=1090|Location.Y=340|Corner.X=1090|Corner.Y=350|LineWidth=1|Color=16711680
|RECORD=13|OwnerIndex=446|IsNotAccesible=T|IndexInSheet=22|OwnerPartId=1|Location.X=1090|Location.Y=370|Corner.X=1090|Corner.Y=360|LineWidth=1|Color=16711680
|RECORD=7|OwnerIndex=446|IsNotAccesible=T|IndexInSheet=23|OwnerPartId=1|LineWidth=1|Color=16711680|AreaColor=16711680|IsSolid=T|LocationCount=3|X1=1090|Y1=346|X2=1096|Y2=353|X3=1084|Y3=353
|RECORD=13|OwnerIndex=446|IsNotAccesible=T|IndexInSheet=24|OwnerPartId=1|Location.X=1084|Location.Y=344|Corner.X=1086|Corner.Y=346|LineWidth=1|Color=16711680
|RECORD=13|OwnerIndex=446|IsNotAccesible=T|IndexInSheet=25|OwnerPartId=1|Location.X=1096|Location.Y=348|Corner.X=1094|Corner.Y=346|LineWidth=1|Color=16711680
|RECORD=13|OwnerIndex=446|IsNotAccesible=T|IndexInSheet=26|OwnerPartId=1|Location.X=1094|Location.Y=346|Corner.X=1086|Corner.Y=346|LineWidth=1|Color=16711680
|RECORD=7|OwnerIndex=446|IsNotAccesible=T|IndexInSheet=27|OwnerPartId=1|LineWidth=1|Color=16711680|AreaColor=16711680|IsSolid=T|LocationCount=3|X1=1090|Y1=364|X2=1084|Y2=357|X3=1096|Y3=357
|RECORD=13|OwnerIndex=446|IsNotAccesible=T|IndexInSheet=28|OwnerPartId=1|Location.X=1084|Location.Y=362|Corner.X=1086|Corner.Y=364|LineWidth=1|Color=16711680
|RECORD=13|OwnerIndex=446|IsNotAccesible=T|IndexInSheet=29|OwnerPartId=1|Location.X=1096|Location.Y=366|Corner.X=1094|Corner.Y=364|LineWidth=1|Color=16711680
|RECORD=13|OwnerIndex=446|IsNotAccesible=T|IndexInSheet=30|OwnerPartId=1|Location.X=1086|Location.Y=364|Corner.X=1094|Corner.Y=364|LineWidth=1|Color=16711680
|RECORD=41|OwnerIndex=446|IndexInSheet=31|OwnerPartId=-1|Location.X=1083|Location.Y=392|Color=8388608|FontID=1|IsHidden=T|Text=<VALENTIUM>|Name=VALENTIUM PART NUM
|RECORD=34|OwnerIndex=446|IndexInSheet=-1|OwnerPartId=-1|Location.X=1097|Location.Y=357|Color=8388608|FontID=3|Text=D17|Name=Designator|ReadOnlyState=1
|RECORD=41|OwnerIndex=446|IndexInSheet=-1|OwnerPartId=-1|Location.X=1083|Location.Y=392|Color=8388608|FontID=2|IsHidden=T|Text=SMCJ6.5CA|Name=Comment
|RECORD=44|OwnerIndex=446
|RECORD=45|OwnerIndex=483|IndexInSheet=-1|Description=Molded Diode, SMC, 2-Leads, Body 6.85x5.90mm, IPC Medium Density|UseComponentLibrary=T|ModelName=DIOM6959X26N|ModelType=PCBLIB|DatafileCount=1|ModelDatafileEntity0=DIOM6959X26N|ModelDatafileKind0=PCBLib|IsCurrent=T|DatalinksLocked=T|DatabaseDatalinksLocked=T|IntegratedModel=T|DatabaseModel=T
|RECORD=46|OwnerIndex=484
|RECORD=48|OwnerIndex=484
|RECORD=1|LibReference=SMCJ6.5CA|ComponentDescription=DIO, TVS, SMCJ6.5, 6.5V, BIDIR, 1.5KW, SMC|PartCount=2|DisplayModeCount=1|IndexInSheet=56|OwnerPartId=-1|Location.X=1370|Location.Y=320|Orientation=1|CurrentPartId=1|LibraryPath=*|SourceLibraryName=Passives.IntLib|TargetFileName=*|AreaColor=11599871|Color=128|PartIDLocked=F|DesignItemId=SMCJ6.5CA|AllPinCount=2
|RECORD=41|OwnerIndex=487|OwnerPartId=-1|Location.X=1363|Location.Y=392|Color=8388608|FontID=2|IsHidden=T|Text=SMCJ6.5CA|Name=MFG PART NUM
|RECORD=41|OwnerIndex=487|IndexInSheet=1|OwnerPartId=-1|Location.X=1363|Location.Y=392|Color=8388608|FontID=2|IsHidden=T|Text=9/4/2013|Name=MODIFY DATE
|RECORD=41|OwnerIndex=487|IndexInSheet=2|OwnerPartId=-1|Location.X=1363|Location.Y=392|Color=8388608|FontID=2|IsHidden=T|Text=LITTELFUSE|Name=MFG NAME
|RECORD=41|OwnerIndex=487|IndexInSheet=3|OwnerPartId=-1|Location.X=1363|Location.Y=392|Color=8388608|FontID=2|IsHidden=T|Text=DIO, TVS|Name=CATEGORY
|RECORD=41|OwnerIndex=487|IndexInSheet=4|OwnerPartId=-1|Location.X=1363|Location.Y=392|Color=8388608|FontID=2|IsHidden=T|Name=DATE
|RECORD=41|OwnerIndex=487|IndexInSheet=5|OwnerPartId=-1|Location.X=1363|Location.Y=392|Color=8388608|FontID=2|IsHidden=T|Text=150C|Name=MAXTEMP
|RECORD=41|OwnerIndex=487|IndexInSheet=6|OwnerPartId=-1|Location.X=1363|Location.Y=392|Color=8388608|FontID=2|IsHidden=T|Text=-55C|Name=MINTEMP
|RECORD=41|OwnerIndex=487|IndexInSheet=7|OwnerPartId=-1|Location.X=1363|Location.Y=392|Color=8388608|FontID=2|IsHidden=T|Text=SMCJ|Name=OTHER
|RECORD=41|OwnerIndex=487|IndexInSheet=8|OwnerPartId=-1|Location.X=1363|Location.Y=392|Color=8388608|FontID=2|IsHidden=T|Text=6.5V|Name=P1
|RECORD=41|OwnerIndex=487|IndexInSheet=9|OwnerPartId=-1|Location.X=1363|Location.Y=392|Color=8388608|FontID=2|IsHidden=T|Text=BIDIR|Name=P2
|RECORD=41|OwnerIndex=487|IndexInSheet=10|OwnerPartId=-1|Location.X=1363|Location.Y=392|Color=8388608|FontID=2|IsHidden=T|Text=1.5KW|Name=P3
|RECORD=41|OwnerIndex=487|IndexInSheet=11|OwnerPartId=-1|Location.X=1363|Location.Y=392|Color=8388608|FontID=2|IsHidden=T|Text=SMC|Name=SIZE
|RECORD=41|OwnerIndex=487|IndexInSheet=12|OwnerPartId=-1|Location.X=1363|Location.Y=392|Color=8388608|FontID=2|IsHidden=T|Name=SUB
|RECORD=41|OwnerIndex=487|IndexInSheet=13|OwnerPartId=-1|Location.X=1363|Location.Y=392|Color=8388608|FontID=1|IsHidden=T|Text=*|Name=SHEETPART
|RECORD=41|OwnerIndex=487|IndexInSheet=14|OwnerPartId=-1|Location.X=1363|Location.Y=392|Color=8388608|FontID=1|IsHidden=T|Text=Digi-Key|Name=Supplier 1|ReadOnlyState=3
|RECORD=41|OwnerIndex=487|IndexInSheet=15|OwnerPartId=-1|Location.X=1363|Location.Y=392|Color=8388608|FontID=1|IsHidden=T|Text=SMCJ6.5CALFCT-ND|Name=Supplier Part Number 1|ReadOnlyState=3
|RECORD=41|OwnerIndex=487|IndexInSheet=16|OwnerPartId=-1|Location.X=1363|Location.Y=392|Color=8388608|FontID=1|IsHidden=T|Text=DIO, TVS, SMCJ6.5, 6.5V, BIDIR, 1.5KW, SMC|Name=DESC
|RECORD=41|OwnerIndex=487|IndexInSheet=17|OwnerPartId=-1|Location.X=1377|Location.Y=345|Color=8388608|FontID=2|Text=SMCJ6.5|Name=VALUE
|RECORD=2|OwnerIndex=487|OwnerPartId=1|FormalType=1|Electrical=4|PinConglomerate=35|PinLength=20|Location.X=1370|Location.Y=340|Name=K|Designator=K|SwapIdPin=2|SwapIDPart=1|PinPropagationDelay=0.000000E+000
|RECORD=2|OwnerIndex=487|OwnerPartId=1|FormalType=1|Electrical=4|PinConglomerate=33|PinLength=20|Location.X=1370|Location.Y=370|Name=A|Designator=A|SwapIdPin=1|SwapIDPart=1|PinPropagationDelay=0.000000E+000
|RECORD=13|OwnerIndex=487|IsNotAccesible=T|IndexInSheet=20|OwnerPartId=1|Location.X=1370|Location.Y=350|Corner.X=1370|Corner.Y=360|LineWidth=1|Color=16711680
|RECORD=13|OwnerIndex=487|IsNotAccesible=T|IndexInSheet=21|OwnerPartId=1|Location.X=1370|Location.Y=340|Corner.X=1370|Corner.Y=350|LineWidth=1|Color=16711680
|RECORD=13|OwnerIndex=487|IsNotAccesible=T|IndexInSheet=22|OwnerPartId=1|Location.X=1370|Location.Y=370|Corner.X=1370|Corner.Y=360|LineWidth=1|Color=16711680
|RECORD=7|OwnerIndex=487|IsNotAccesible=T|IndexInSheet=23|OwnerPartId=1|LineWidth=1|Color=16711680|AreaColor=16711680|IsSolid=T|LocationCount=3|X1=1370|Y1=346|X2=1376|Y2=353|X3=1364|Y3=353
|RECORD=13|OwnerIndex=487|IsNotAccesible=T|IndexInSheet=24|OwnerPartId=1|Location.X=1364|Location.Y=344|Corner.X=1366|Corner.Y=346|LineWidth=1|Color=16711680
|RECORD=13|OwnerIndex=487|IsNotAccesible=T|IndexInSheet=25|OwnerPartId=1|Location.X=1376|Location.Y=348|Corner.X=1374|Corner.Y=346|LineWidth=1|Color=16711680
|RECORD=13|OwnerIndex=487|IsNotAccesible=T|IndexInSheet=26|OwnerPartId=1|Location.X=1374|Location.Y=346|Corner.X=1366|Corner.Y=346|LineWidth=1|Color=16711680
|RECORD=7|OwnerIndex=487|IsNotAccesible=T|IndexInSheet=27|OwnerPartId=1|LineWidth=1|Color=16711680|AreaColor=16711680|IsSolid=T|LocationCount=3|X1=1370|Y1=364|X2=1364|Y2=357|X3=1376|Y3=357
|RECORD=13|OwnerIndex=487|IsNotAccesible=T|IndexInSheet=28|OwnerPartId=1|Location.X=1364|Location.Y=362|Corner.X=1366|Corner.Y=364|LineWidth=1|Color=16711680
|RECORD=13|OwnerIndex=487|IsNotAccesible=T|IndexInSheet=29|OwnerPartId=1|Location.X=1376|Location.Y=366|Corner.X=1374|Corner.Y=364|LineWidth=1|Color=16711680
|RECORD=13|OwnerIndex=487|IsNotAccesible=T|IndexInSheet=30|OwnerPartId=1|Location.X=1366|Location.Y=364|Corner.X=1374|Corner.Y=364|LineWidth=1|Color=16711680
|RECORD=41|OwnerIndex=487|IndexInSheet=31|OwnerPartId=-1|Location.X=1363|Location.Y=392|Color=8388608|FontID=1|IsHidden=T|Text=<VALENTIUM>|Name=VALENTIUM PART NUM
|RECORD=34|OwnerIndex=487|IndexInSheet=-1|OwnerPartId=-1|Location.X=1377|Location.Y=357|Color=8388608|FontID=3|Text=D18|Name=Designator|ReadOnlyState=1
|RECORD=41|OwnerIndex=487|IndexInSheet=-1|OwnerPartId=-1|Location.X=1363|Location.Y=392|Color=8388608|FontID=2|IsHidden=T|Text=SMCJ6.5CA|Name=Comment
|RECORD=44|OwnerIndex=487
|RECORD=45|OwnerIndex=524|IndexInSheet=-1|Description=Molded Diode, SMC, 2-Leads, Body 6.85x5.90mm, IPC Medium Density|UseComponentLibrary=T|ModelName=DIOM6959X26N|ModelType=PCBLIB|DatafileCount=1|ModelDatafileEntity0=DIOM6959X26N|ModelDatafileKind0=PCBLib|IsCurrent=T|DatalinksLocked=T|DatabaseDatalinksLocked=T|IntegratedModel=T|DatabaseModel=T
|RECORD=46|OwnerIndex=525
|RECORD=48|OwnerIndex=525
|RECORD=1|LibReference=SMCJ6.5CA|ComponentDescription=DIO, TVS, SMCJ6.5, 6.5V, BIDIR, 1.5KW, SMC|PartCount=2|DisplayModeCount=1|IndexInSheet=57|OwnerPartId=-1|Location.X=1090|Location.Y=580|Orientation=1|CurrentPartId=1|LibraryPath=*|SourceLibraryName=Passives.IntLib|TargetFileName=*|AreaColor=11599871|Color=128|PartIDLocked=F|DesignItemId=SMCJ6.5CA|AllPinCount=2
|RECORD=41|OwnerIndex=528|OwnerPartId=-1|Location.X=1083|Location.Y=652|Color=8388608|FontID=2|IsHidden=T|Text=SMCJ6.5CA|Name=MFG PART NUM
|RECORD=41|OwnerIndex=528|IndexInSheet=1|OwnerPartId=-1|Location.X=1083|Location.Y=652|Color=8388608|FontID=2|IsHidden=T|Text=9/4/2013|Name=MODIFY DATE
|RECORD=41|OwnerIndex=528|IndexInSheet=2|OwnerPartId=-1|Location.X=1083|Location.Y=652|Color=8388608|FontID=2|IsHidden=T|Text=LITTELFUSE|Name=MFG NAME
|RECORD=41|OwnerIndex=528|IndexInSheet=3|OwnerPartId=-1|Location.X=1083|Location.Y=652|Color=8388608|FontID=2|IsHidden=T|Text=DIO, TVS|Name=CATEGORY
|RECORD=41|OwnerIndex=528|IndexInSheet=4|OwnerPartId=-1|Location.X=1083|Location.Y=652|Color=8388608|FontID=2|IsHidden=T|Name=DATE
|RECORD=41|OwnerIndex=528|IndexInSheet=5|OwnerPartId=-1|Location.X=1083|Location.Y=652|Color=8388608|FontID=2|IsHidden=T|Text=150C|Name=MAXTEMP
|RECORD=41|OwnerIndex=528|IndexInSheet=6|OwnerPartId=-1|Location.X=1083|Location.Y=652|Color=8388608|FontID=2|IsHidden=T|Text=-55C|Name=MINTEMP
|RECORD=41|OwnerIndex=528|IndexInSheet=7|OwnerPartId=-1|Location.X=1083|Location.Y=652|Color=8388608|FontID=2|IsHidden=T|Text=SMCJ|Name=OTHER
|RECORD=41|OwnerIndex=528|IndexInSheet=8|OwnerPartId=-1|Location.X=1083|Location.Y=652|Color=8388608|FontID=2|IsHidden=T|Text=6.5V|Name=P1
|RECORD=41|OwnerIndex=528|IndexInSheet=9|OwnerPartId=-1|Location.X=1083|Location.Y=652|Color=8388608|FontID=2|IsHidden=T|Text=BIDIR|Name=P2
|RECORD=41|OwnerIndex=528|IndexInSheet=10|OwnerPartId=-1|Location.X=1083|Location.Y=652|Color=8388608|FontID=2|IsHidden=T|Text=1.5KW|Name=P3
|RECORD=41|OwnerIndex=528|IndexInSheet=11|OwnerPartId=-1|Location.X=1083|Location.Y=652|Color=8388608|FontID=2|IsHidden=T|Text=SMC|Name=SIZE
|RECORD=41|OwnerIndex=528|IndexInSheet=12|OwnerPartId=-1|Location.X=1083|Location.Y=652|Color=8388608|FontID=2|IsHidden=T|Name=SUB
|RECORD=41|OwnerIndex=528|IndexInSheet=13|OwnerPartId=-1|Location.X=1083|Location.Y=652|Color=8388608|FontID=1|IsHidden=T|Text=*|Name=SHEETPART
|RECORD=41|OwnerIndex=528|IndexInSheet=14|OwnerPartId=-1|Location.X=1083|Location.Y=652|Color=8388608|FontID=1|IsHidden=T|Text=Digi-Key|Name=Supplier 1|ReadOnlyState=3
|RECORD=41|OwnerIndex=528|IndexInSheet=15|OwnerPartId=-1|Location.X=1083|Location.Y=652|Color=8388608|FontID=1|IsHidden=T|Text=SMCJ6.5CALFCT-ND|Name=Supplier Part Number 1|ReadOnlyState=3
|RECORD=41|OwnerIndex=528|IndexInSheet=16|OwnerPartId=-1|Location.X=1083|Location.Y=652|Color=8388608|FontID=1|IsHidden=T|Text=DIO, TVS, SMCJ6.5, 6.5V, BIDIR, 1.5KW, SMC|Name=DESC
|RECORD=41|OwnerIndex=528|IndexInSheet=17|OwnerPartId=-1|Location.X=1097|Location.Y=605|Color=8388608|FontID=2|Text=SMCJ6.5|Name=VALUE
|RECORD=2|OwnerIndex=528|OwnerPartId=1|FormalType=1|Electrical=4|PinConglomerate=35|PinLength=20|Location.X=1090|Location.Y=600|Name=K|Designator=K|SwapIdPin=2|SwapIDPart=1|PinPropagationDelay=0.000000E+000
|RECORD=2|OwnerIndex=528|OwnerPartId=1|FormalType=1|Electrical=4|PinConglomerate=33|PinLength=20|Location.X=1090|Location.Y=630|Name=A|Designator=A|SwapIdPin=1|SwapIDPart=1|PinPropagationDelay=0.000000E+000
|RECORD=13|OwnerIndex=528|IsNotAccesible=T|IndexInSheet=20|OwnerPartId=1|Location.X=1090|Location.Y=610|Corner.X=1090|Corner.Y=620|LineWidth=1|Color=16711680
|RECORD=13|OwnerIndex=528|IsNotAccesible=T|IndexInSheet=21|OwnerPartId=1|Location.X=1090|Location.Y=600|Corner.X=1090|Corner.Y=610|LineWidth=1|Color=16711680
|RECORD=13|OwnerIndex=528|IsNotAccesible=T|IndexInSheet=22|OwnerPartId=1|Location.X=1090|Location.Y=630|Corner.X=1090|Corner.Y=620|LineWidth=1|Color=16711680
|RECORD=7|OwnerIndex=528|IsNotAccesible=T|IndexInSheet=23|OwnerPartId=1|LineWidth=1|Color=16711680|AreaColor=16711680|IsSolid=T|LocationCount=3|X1=1090|Y1=606|X2=1096|Y2=613|X3=1084|Y3=613
|RECORD=13|OwnerIndex=528|IsNotAccesible=T|IndexInSheet=24|OwnerPartId=1|Location.X=1084|Location.Y=604|Corner.X=1086|Corner.Y=606|LineWidth=1|Color=16711680
|RECORD=13|OwnerIndex=528|IsNotAccesible=T|IndexInSheet=25|OwnerPartId=1|Location.X=1096|Location.Y=608|Corner.X=1094|Corner.Y=606|LineWidth=1|Color=16711680
|RECORD=13|OwnerIndex=528|IsNotAccesible=T|IndexInSheet=26|OwnerPartId=1|Location.X=1094|Location.Y=606|Corner.X=1086|Corner.Y=606|LineWidth=1|Color=16711680
|RECORD=7|OwnerIndex=528|IsNotAccesible=T|IndexInSheet=27|OwnerPartId=1|LineWidth=1|Color=16711680|AreaColor=16711680|IsSolid=T|LocationCount=3|X1=1090|Y1=624|X2=1084|Y2=617|X3=1096|Y3=617
|RECORD=13|OwnerIndex=528|IsNotAccesible=T|IndexInSheet=28|OwnerPartId=1|Location.X=1084|Location.Y=622|Corner.X=1086|Corner.Y=624|LineWidth=1|Color=16711680
|RECORD=13|OwnerIndex=528|IsNotAccesible=T|IndexInSheet=29|OwnerPartId=1|Location.X=1096|Location.Y=626|Corner.X=1094|Corner.Y=624|LineWidth=1|Color=16711680
|RECORD=13|OwnerIndex=528|IsNotAccesible=T|IndexInSheet=30|OwnerPartId=1|Location.X=1086|Location.Y=624|Corner.X=1094|Corner.Y=624|LineWidth=1|Color=16711680
|RECORD=41|OwnerIndex=528|IndexInSheet=31|OwnerPartId=-1|Location.X=1083|Location.Y=652|Color=8388608|FontID=1|IsHidden=T|Text=<VALENTIUM>|Name=VALENTIUM PART NUM
|RECORD=34|OwnerIndex=528|IndexInSheet=-1|OwnerPartId=-1|Location.X=1097|Location.Y=617|Color=8388608|FontID=3|Text=D16|Name=Designator|ReadOnlyState=1
|RECORD=41|OwnerIndex=528|IndexInSheet=-1|OwnerPartId=-1|Location.X=1083|Location.Y=652|Color=8388608|FontID=2|IsHidden=T|Text=SMCJ6.5CA|Name=Comment
|RECORD=44|OwnerIndex=528
|RECORD=45|OwnerIndex=565|IndexInSheet=-1|Description=Molded Diode, SMC, 2-Leads, Body 6.85x5.90mm, IPC Medium Density|UseComponentLibrary=T|ModelName=DIOM6959X26N|ModelType=PCBLIB|DatafileCount=1|ModelDatafileEntity0=DIOM6959X26N|ModelDatafileKind0=PCBLib|IsCurrent=T|DatalinksLocked=T|DatabaseDatalinksLocked=T|IntegratedModel=T|DatabaseModel=T
|RECORD=46|OwnerIndex=566
|RECORD=48|OwnerIndex=566
|RECORD=17|IndexInSheet=58|OwnerPartId=-1|Style=4|ShowNetName=T|Location.X=1090|Location.Y=300|Orientation=3|Color=128|FontID=1|Text=GND
|RECORD=17|IndexInSheet=59|OwnerPartId=-1|Style=4|ShowNetName=T|Location.X=1370|Location.Y=300|Orientation=3|Color=128|FontID=1|Text=GND
|RECORD=17|IndexInSheet=60|OwnerPartId=-1|Style=4|ShowNetName=T|Location.X=1370|Location.Y=570|Orientation=3|Color=128|FontID=1|Text=GND
|RECORD=17|IndexInSheet=61|OwnerPartId=-1|Style=4|ShowNetName=T|Location.X=1090|Location.Y=560|Orientation=3|Color=128|FontID=1|Text=GND
|RECORD=17|IndexInSheet=62|OwnerPartId=-1|ShowNetName=T|Location.X=1130|Location.Y=660|Color=255|FontID=1|Text=ANT1|IsCrossSheetConnector=T
|RECORD=17|IndexInSheet=63|OwnerPartId=-1|ShowNetName=T|Location.X=1410|Location.Y=670|Color=255|FontID=1|Text=ANT2|IsCrossSheetConnector=T
|RECORD=17|IndexInSheet=64|OwnerPartId=-1|ShowNetName=T|Location.X=1410|Location.Y=400|Color=255|FontID=1|Text=ANT4|IsCrossSheetConnector=T
|RECORD=17|IndexInSheet=65|OwnerPartId=-1|ShowNetName=T|Location.X=1130|Location.Y=400|Color=255|FontID=1|Text=ANT3|IsCrossSheetConnector=T
|RECORD=4|IndexInSheet=66|OwnerPartId=-1|Location.X=1170|Location.Y=800|Color=8388608|FontID=4|Text=PPS INPUT/OUTPUT
|RECORD=1|LibReference=Res3|ComponentDescription=Resistor|PartCount=2|DisplayModeCount=1|IndexInSheet=67|OwnerPartId=-1|Location.X=1120|Location.Y=470|Orientation=3|CurrentPartId=1|SourceLibraryName=Miscellaneous Devices.IntLib|TargetFileName=*|AreaColor=11599871|Color=128|PartIDLocked=F|DesignItemId=Res3|AllPinCount=2
|RECORD=2|OwnerIndex=578|OwnerPartId=1|FormalType=1|Electrical=4|PinConglomerate=33|PinLength=10|Location.X=1110|Location.Y=470|Name=1|Designator=1|PinPropagationDelay=0.000000E+000
|RECORD=2|OwnerIndex=578|OwnerPartId=1|FormalType=1|Electrical=4|PinConglomerate=35|PinLength=10|Location.X=1110|Location.Y=440|Name=2|Designator=2|PinPropagationDelay=0.000000E+000
|RECORD=6|OwnerIndex=578|IsNotAccesible=T|IndexInSheet=2|OwnerPartId=1|LineWidth=1|Color=16711680|LocationCount=7|X1=1110|Y1=440|X2=1113|Y2=443|X3=1107|Y3=449|X4=1113|Y4=455|X5=1107|Y5=461|X6=1113|Y6=467|X7=1110|Y7=470
|RECORD=41|OwnerIndex=578|IndexInSheet=3|OwnerPartId=-1|Location.X=1106|Location.Y=482|Color=8388608|FontID=1|IsHidden=T|Text=8-Jun-2000|Name=Published
|RECORD=41|OwnerIndex=578|IndexInSheet=4|OwnerPartId=-1|Location.X=1106|Location.Y=482|Color=8388608|FontID=1|IsHidden=T|Text=29-May-2009|Name=LatestRevisionDate
|RECORD=41|OwnerIndex=578|IndexInSheet=5|OwnerPartId=-1|Location.X=1106|Location.Y=482|Color=8388608|FontID=1|IsHidden=T|Text=IPC-7351 Footprint Added.|Name=LatestRevisionNote
|RECORD=41|OwnerIndex=578|IndexInSheet=6|OwnerPartId=-1|Location.X=1106|Location.Y=482|Color=8388608|FontID=1|IsHidden=T|Text=J1-0603|Name=PackageReference
|RECORD=41|OwnerIndex=578|IndexInSheet=7|OwnerPartId=-1|Location.X=1106|Location.Y=482|Color=8388608|FontID=1|IsHidden=T|Text=Altium Limited|Name=Publisher
|RECORD=41|OwnerIndex=578|IndexInSheet=8|OwnerPartId=-1|Location.X=1106|Location.Y=482|Color=8388608|FontID=1|IsHidden=T|Text=Chip Resistor|Name=PackageDescription
|RECORD=41|OwnerIndex=578|IndexInSheet=9|OwnerPartId=-1|Location.X=1114|Location.Y=441|Color=8388608|FontID=1|Text=0 Ohm|Name=Value
|RECORD=34|OwnerIndex=578|IndexInSheet=-1|OwnerPartId=-1|Location.X=1114|Location.Y=461|Color=8388608|FontID=1|Text=R31|Name=Designator|ReadOnlyState=1
|RECORD=41|OwnerIndex=578|IndexInSheet=-1|OwnerPartId=-1|Location.X=1114|Location.Y=451|Color=8388608|FontID=1|Text=MAC10M|Name=Comment
|RECORD=44|OwnerIndex=578
|RECORD=45|OwnerIndex=593|IndexInSheet=-1|Description=Chip Resistor, Body 1.6x0.8mm, IPC High Density|UseComponentLibrary=T|ModelName=J1-0603|ModelType=PCBLIB|DatafileCount=1|ModelDatafileEntity0=J1-0603|ModelDatafileKind0=PCBLib|IsCurrent=T|DatalinksLocked=T|DatabaseDatalinksLocked=T|IntegratedModel=T|DatabaseModel=T
|RECORD=46|OwnerIndex=594
|RECORD=48|OwnerIndex=594
|RECORD=45|OwnerIndex=593|IndexInSheet=-1|Description=Chip Resistor, Body 3.2x2.5mm, IPC High Density|UseComponentLibrary=T|ModelName=14-1210|ModelType=PCBLIB|DatafileCount=1|ModelDatafileEntity0=14-1210|ModelDatafileKind0=PCBLib|DatalinksLocked=T|DatabaseDatalinksLocked=T|IntegratedModel=T|DatabaseModel=T
|RECORD=46|OwnerIndex=597
|RECORD=48|OwnerIndex=597
|RECORD=45|OwnerIndex=593|IndexInSheet=-1|Description=Chip Resistor, Body 5.0x2.5mm, IPC High Density|UseComponentLibrary=T|ModelName=12Z-2010|ModelType=PCBLIB|DatafileCount=1|ModelDatafileEntity0=12Z-2010|ModelDatafileKind0=PCBLib|DatalinksLocked=T|DatabaseDatalinksLocked=T|IntegratedModel=T|DatabaseModel=T
|RECORD=46|OwnerIndex=600
|RECORD=48|OwnerIndex=600
|RECORD=45|OwnerIndex=593|IndexInSheet=-1|Description=Chip Resistor, Body 6.3x3.2mm, IPC High Density|UseComponentLibrary=T|ModelName=RESC6332|ModelType=PCBLIB|DatafileCount=1|ModelDatafileEntity0=RESC6332|ModelDatafileKind0=PCBLib|DatalinksLocked=T|DatabaseDatalinksLocked=T|IntegratedModel=T|DatabaseModel=T
|RECORD=46|OwnerIndex=603
|RECORD=48|OwnerIndex=603
|RECORD=45|OwnerIndex=593|IndexInSheet=-1|Description=Resistor|UseComponentLibrary=T|ModelName=RESISTOR|ModelType=SIM|IsCurrent=T|DatalinksLocked=T|DatabaseDatalinksLocked=T|IntegratedModel=T|DatabaseModel=T
|RECORD=46|OwnerIndex=606
|RECORD=48|OwnerIndex=606
|RECORD=41|OwnerIndex=608|IndexInSheet=-1|OwnerPartId=-1|Color=8388608|FontID=1|Text=R|Name=Spice Prefix
|RECORD=41|OwnerIndex=608|IndexInSheet=-1|OwnerPartId=-1|Color=8388608|FontID=1|Text=@DESIGNATOR %1 %2 @VALUE|Name=Netlist
|RECORD=41|OwnerIndex=608|IndexInSheet=-1|OwnerPartId=-1|Color=8388608|FontID=1|Text=General|Name=Kind
|RECORD=41|OwnerIndex=608|IndexInSheet=-1|OwnerPartId=-1|Color=8388608|FontID=1|Text=Resistor|Name=SubKind
|RECORD=45|OwnerIndex=593|IndexInSheet=-1|UseComponentLibrary=T|ModelName=Res|ModelType=SI|IsCurrent=T|DatalinksLocked=T|DatabaseDatalinksLocked=T|IntegratedModel=T|DatabaseModel=T
|RECORD=46|OwnerIndex=613
|RECORD=48|OwnerIndex=613
|RECORD=41|OwnerIndex=615|IndexInSheet=-1|OwnerPartId=-1|Color=8388608|FontID=1|Text=Resistor|Name=Type
|RECORD=41|OwnerIndex=615|IndexInSheet=-1|OwnerPartId=-1|Color=8388608|FontID=1|Name=Tech
|RECORD=1|LibReference=Res3|ComponentDescription=Resistor|PartCount=2|DisplayModeCount=1|IndexInSheet=68|OwnerPartId=-1|Location.X=1120|Location.Y=730|Orientation=3|CurrentPartId=1|SourceLibraryName=Miscellaneous Devices.IntLib|TargetFileName=*|AreaColor=11599871|Color=128|PartIDLocked=F|DesignItemId=Res3|AllPinCount=2
|RECORD=2|OwnerIndex=618|OwnerPartId=1|FormalType=1|Electrical=4|PinConglomerate=33|PinLength=10|Location.X=1110|Location.Y=730|Name=1|Designator=1|PinPropagationDelay=0.000000E+000
|RECORD=2|OwnerIndex=618|OwnerPartId=1|FormalType=1|Electrical=4|PinConglomerate=35|PinLength=10|Location.X=1110|Location.Y=700|Name=2|Designator=2|PinPropagationDelay=0.000000E+000
|RECORD=6|OwnerIndex=618|IsNotAccesible=T|IndexInSheet=2|OwnerPartId=1|LineWidth=1|Color=16711680|LocationCount=7|X1=1110|Y1=700|X2=1113|Y2=703|X3=1107|Y3=709|X4=1113|Y4=715|X5=1107|Y5=721|X6=1113|Y6=727|X7=1110|Y7=730
|RECORD=41|OwnerIndex=618|IndexInSheet=3|OwnerPartId=-1|Location.X=1106|Location.Y=742|Color=8388608|FontID=1|IsHidden=T|Text=8-Jun-2000|Name=Published
|RECORD=41|OwnerIndex=618|IndexInSheet=4|OwnerPartId=-1|Location.X=1106|Location.Y=742|Color=8388608|FontID=1|IsHidden=T|Text=29-May-2009|Name=LatestRevisionDate
|RECORD=41|OwnerIndex=618|IndexInSheet=5|OwnerPartId=-1|Location.X=1106|Location.Y=742|Color=8388608|FontID=1|IsHidden=T|Text=IPC-7351 Footprint Added.|Name=LatestRevisionNote
|RECORD=41|OwnerIndex=618|IndexInSheet=6|OwnerPartId=-1|Location.X=1106|Location.Y=742|Color=8388608|FontID=1|IsHidden=T|Text=J1-0603|Name=PackageReference
|RECORD=41|OwnerIndex=618|IndexInSheet=7|OwnerPartId=-1|Location.X=1106|Location.Y=742|Color=8388608|FontID=1|IsHidden=T|Text=Altium Limited|Name=Publisher
|RECORD=41|OwnerIndex=618|IndexInSheet=8|OwnerPartId=-1|Location.X=1106|Location.Y=742|Color=8388608|FontID=1|IsHidden=T|Text=Chip Resistor|Name=PackageDescription
|RECORD=41|OwnerIndex=618|IndexInSheet=9|OwnerPartId=-1|Location.X=1114|Location.Y=701|Color=8388608|FontID=1|Text=0 Ohm|Name=Value
|RECORD=34|OwnerIndex=618|IndexInSheet=-1|OwnerPartId=-1|Location.X=1114|Location.Y=721|Color=8388608|FontID=1|Text=R15|Name=Designator|ReadOnlyState=1
|RECORD=41|OwnerIndex=618|IndexInSheet=-1|OwnerPartId=-1|Location.X=1114|Location.Y=711|Color=8388608|FontID=1|Text=MACPPSI|Name=Comment
|RECORD=44|OwnerIndex=618
|RECORD=45|OwnerIndex=633|IndexInSheet=-1|Description=Chip Resistor, Body 1.6x0.8mm, IPC High Density|UseComponentLibrary=T|ModelName=J1-0603|ModelType=PCBLIB|DatafileCount=1|ModelDatafileEntity0=J1-0603|ModelDatafileKind0=PCBLib|IsCurrent=T|DatalinksLocked=T|DatabaseDatalinksLocked=T|IntegratedModel=T|DatabaseModel=T
|RECORD=46|OwnerIndex=634
|RECORD=48|OwnerIndex=634
|RECORD=45|OwnerIndex=633|IndexInSheet=-1|Description=Chip Resistor, Body 3.2x2.5mm, IPC High Density|UseComponentLibrary=T|ModelName=14-1210|ModelType=PCBLIB|DatafileCount=1|ModelDatafileEntity0=14-1210|ModelDatafileKind0=PCBLib|DatalinksLocked=T|DatabaseDatalinksLocked=T|IntegratedModel=T|DatabaseModel=T
|RECORD=46|OwnerIndex=637
|RECORD=48|OwnerIndex=637
|RECORD=45|OwnerIndex=633|IndexInSheet=-1|Description=Chip Resistor, Body 5.0x2.5mm, IPC High Density|UseComponentLibrary=T|ModelName=12Z-2010|ModelType=PCBLIB|DatafileCount=1|ModelDatafileEntity0=12Z-2010|ModelDatafileKind0=PCBLib|DatalinksLocked=T|DatabaseDatalinksLocked=T|IntegratedModel=T|DatabaseModel=T
|RECORD=46|OwnerIndex=640
|RECORD=48|OwnerIndex=640
|RECORD=45|OwnerIndex=633|IndexInSheet=-1|Description=Chip Resistor, Body 6.3x3.2mm, IPC High Density|UseComponentLibrary=T|ModelName=RESC6332|ModelType=PCBLIB|DatafileCount=1|ModelDatafileEntity0=RESC6332|ModelDatafileKind0=PCBLib|DatalinksLocked=T|DatabaseDatalinksLocked=T|IntegratedModel=T|DatabaseModel=T
|RECORD=46|OwnerIndex=643
|RECORD=48|OwnerIndex=643
|RECORD=45|OwnerIndex=633|IndexInSheet=-1|Description=Resistor|UseComponentLibrary=T|ModelName=RESISTOR|ModelType=SIM|IsCurrent=T|DatalinksLocked=T|DatabaseDatalinksLocked=T|IntegratedModel=T|DatabaseModel=T
|RECORD=46|OwnerIndex=646
|RECORD=48|OwnerIndex=646
|RECORD=41|OwnerIndex=648|IndexInSheet=-1|OwnerPartId=-1|Color=8388608|FontID=1|Text=R|Name=Spice Prefix
|RECORD=41|OwnerIndex=648|IndexInSheet=-1|OwnerPartId=-1|Color=8388608|FontID=1|Text=@DESIGNATOR %1 %2 @VALUE|Name=Netlist
|RECORD=41|OwnerIndex=648|IndexInSheet=-1|OwnerPartId=-1|Color=8388608|FontID=1|Text=General|Name=Kind
|RECORD=41|OwnerIndex=648|IndexInSheet=-1|OwnerPartId=-1|Color=8388608|FontID=1|Text=Resistor|Name=SubKind
|RECORD=45|OwnerIndex=633|IndexInSheet=-1|UseComponentLibrary=T|ModelName=Res|ModelType=SI|IsCurrent=T|DatalinksLocked=T|DatabaseDatalinksLocked=T|IntegratedModel=T|DatabaseModel=T
|RECORD=46|OwnerIndex=653
|RECORD=48|OwnerIndex=653
|RECORD=41|OwnerIndex=655|IndexInSheet=-1|OwnerPartId=-1|Color=8388608|FontID=1|Text=Resistor|Name=Type
|RECORD=41|OwnerIndex=655|IndexInSheet=-1|OwnerPartId=-1|Color=8388608|FontID=1|Name=Tech
|RECORD=1|LibReference=Res3|ComponentDescription=Resistor|PartCount=2|DisplayModeCount=1|IndexInSheet=69|OwnerPartId=-1|Location.X=1400|Location.Y=740|Orientation=3|CurrentPartId=1|SourceLibraryName=Miscellaneous Devices.IntLib|TargetFileName=*|AreaColor=11599871|Color=128|PartIDLocked=F|DesignItemId=Res3|AllPinCount=2
|RECORD=2|OwnerIndex=658|OwnerPartId=1|FormalType=1|Electrical=4|PinConglomerate=33|PinLength=10|Location.X=1390|Location.Y=740|Name=1|Designator=1|PinPropagationDelay=0.000000E+000
|RECORD=2|OwnerIndex=658|OwnerPartId=1|FormalType=1|Electrical=4|PinConglomerate=35|PinLength=10|Location.X=1390|Location.Y=710|Name=2|Designator=2|PinPropagationDelay=0.000000E+000
|RECORD=6|OwnerIndex=658|IsNotAccesible=T|IndexInSheet=2|OwnerPartId=1|LineWidth=1|Color=16711680|LocationCount=7|X1=1390|Y1=710|X2=1393|Y2=713|X3=1387|Y3=719|X4=1393|Y4=725|X5=1387|Y5=731|X6=1393|Y6=737|X7=1390|Y7=740
|RECORD=41|OwnerIndex=658|IndexInSheet=3|OwnerPartId=-1|Location.X=1386|Location.Y=752|Color=8388608|FontID=1|IsHidden=T|Text=8-Jun-2000|Name=Published
|RECORD=41|OwnerIndex=658|IndexInSheet=4|OwnerPartId=-1|Location.X=1386|Location.Y=752|Color=8388608|FontID=1|IsHidden=T|Text=29-May-2009|Name=LatestRevisionDate
|RECORD=41|OwnerIndex=658|IndexInSheet=5|OwnerPartId=-1|Location.X=1386|Location.Y=752|Color=8388608|FontID=1|IsHidden=T|Text=IPC-7351 Footprint Added.|Name=LatestRevisionNote
|RECORD=41|OwnerIndex=658|IndexInSheet=6|OwnerPartId=-1|Location.X=1386|Location.Y=752|Color=8388608|FontID=1|IsHidden=T|Text=J1-0603|Name=PackageReference
|RECORD=41|OwnerIndex=658|IndexInSheet=7|OwnerPartId=-1|Location.X=1386|Location.Y=752|Color=8388608|FontID=1|IsHidden=T|Text=Altium Limited|Name=Publisher
|RECORD=41|OwnerIndex=658|IndexInSheet=8|OwnerPartId=-1|Location.X=1386|Location.Y=752|Color=8388608|FontID=1|IsHidden=T|Text=Chip Resistor|Name=PackageDescription
|RECORD=41|OwnerIndex=658|IndexInSheet=9|OwnerPartId=-1|Location.X=1394|Location.Y=711|Color=8388608|FontID=1|Text=0 Ohm|Name=Value
|RECORD=34|OwnerIndex=658|IndexInSheet=-1|OwnerPartId=-1|Location.X=1394|Location.Y=731|Color=8388608|FontID=1|Text=R14|Name=Designator|ReadOnlyState=1
|RECORD=41|OwnerIndex=658|IndexInSheet=-1|OwnerPartId=-1|Location.X=1394|Location.Y=721|Color=8388608|FontID=1|Text=MACPPSO|Name=Comment
|RECORD=44|OwnerIndex=658
|RECORD=45|OwnerIndex=673|IndexInSheet=-1|Description=Chip Resistor, Body 1.6x0.8mm, IPC High Density|UseComponentLibrary=T|ModelName=J1-0603|ModelType=PCBLIB|DatafileCount=1|ModelDatafileEntity0=J1-0603|ModelDatafileKind0=PCBLib|IsCurrent=T|DatalinksLocked=T|DatabaseDatalinksLocked=T|IntegratedModel=T|DatabaseModel=T
|RECORD=46|OwnerIndex=674
|RECORD=48|OwnerIndex=674
|RECORD=45|OwnerIndex=673|IndexInSheet=-1|Description=Chip Resistor, Body 3.2x2.5mm, IPC High Density|UseComponentLibrary=T|ModelName=14-1210|ModelType=PCBLIB|DatafileCount=1|ModelDatafileEntity0=14-1210|ModelDatafileKind0=PCBLib|DatalinksLocked=T|DatabaseDatalinksLocked=T|IntegratedModel=T|DatabaseModel=T
|RECORD=46|OwnerIndex=677
|RECORD=48|OwnerIndex=677
|RECORD=45|OwnerIndex=673|IndexInSheet=-1|Description=Chip Resistor, Body 5.0x2.5mm, IPC High Density|UseComponentLibrary=T|ModelName=12Z-2010|ModelType=PCBLIB|DatafileCount=1|ModelDatafileEntity0=12Z-2010|ModelDatafileKind0=PCBLib|DatalinksLocked=T|DatabaseDatalinksLocked=T|IntegratedModel=T|DatabaseModel=T
|RECORD=46|OwnerIndex=680
|RECORD=48|OwnerIndex=680
|RECORD=45|OwnerIndex=673|IndexInSheet=-1|Description=Chip Resistor, Body 6.3x3.2mm, IPC High Density|UseComponentLibrary=T|ModelName=RESC6332|ModelType=PCBLIB|DatafileCount=1|ModelDatafileEntity0=RESC6332|ModelDatafileKind0=PCBLib|DatalinksLocked=T|DatabaseDatalinksLocked=T|IntegratedModel=T|DatabaseModel=T
|RECORD=46|OwnerIndex=683
|RECORD=48|OwnerIndex=683
|RECORD=45|OwnerIndex=673|IndexInSheet=-1|Description=Resistor|UseComponentLibrary=T|ModelName=RESISTOR|ModelType=SIM|IsCurrent=T|DatalinksLocked=T|DatabaseDatalinksLocked=T|IntegratedModel=T|DatabaseModel=T
|RECORD=46|OwnerIndex=686
|RECORD=48|OwnerIndex=686
|RECORD=41|OwnerIndex=688|IndexInSheet=-1|OwnerPartId=-1|Color=8388608|FontID=1|Text=R|Name=Spice Prefix
|RECORD=41|OwnerIndex=688|IndexInSheet=-1|OwnerPartId=-1|Color=8388608|FontID=1|Text=@DESIGNATOR %1 %2 @VALUE|Name=Netlist
|RECORD=41|OwnerIndex=688|IndexInSheet=-1|OwnerPartId=-1|Color=8388608|FontID=1|Text=General|Name=Kind
|RECORD=41|OwnerIndex=688|IndexInSheet=-1|OwnerPartId=-1|Color=8388608|FontID=1|Text=Resistor|Name=SubKind
|RECORD=45|OwnerIndex=673|IndexInSheet=-1|UseComponentLibrary=T|ModelName=Res|ModelType=SI|IsCurrent=T|DatalinksLocked=T|DatabaseDatalinksLocked=T|IntegratedModel=T|DatabaseModel=T
|RECORD=46|OwnerIndex=693
|RECORD=48|OwnerIndex=693
|RECORD=41|OwnerIndex=695|IndexInSheet=-1|OwnerPartId=-1|Color=8388608|FontID=1|Text=Resistor|Name=Type
|RECORD=41|OwnerIndex=695|IndexInSheet=-1|OwnerPartId=-1|Color=8388608|FontID=1|Name=Tech
|RECORD=17|IndexInSheet=70|OwnerPartId=-1|ShowNetName=T|Location.X=1430|Location.Y=490|Color=255|FontID=1|Text=GPS1_TP1|IsCrossSheetConnector=T
|RECORD=1|LibReference=Res3|ComponentDescription=Resistor|PartCount=2|DisplayModeCount=1|IndexInSheet=71|OwnerPartId=-1|Location.X=1400|Location.Y=470|Orientation=3|CurrentPartId=1|SourceLibraryName=Miscellaneous Devices.IntLib|TargetFileName=*|AreaColor=11599871|Color=128|PartIDLocked=F|DesignItemId=Res3|AllPinCount=2
|RECORD=2|OwnerIndex=699|OwnerPartId=1|FormalType=1|Electrical=4|PinConglomerate=33|PinLength=10|Location.X=1390|Location.Y=470|Name=1|Designator=1|PinPropagationDelay=0.000000E+000
|RECORD=2|OwnerIndex=699|OwnerPartId=1|FormalType=1|Electrical=4|PinConglomerate=35|PinLength=10|Location.X=1390|Location.Y=440|Name=2|Designator=2|PinPropagationDelay=0.000000E+000
|RECORD=6|OwnerIndex=699|IsNotAccesible=T|IndexInSheet=2|OwnerPartId=1|LineWidth=1|Color=16711680|LocationCount=7|X1=1390|Y1=440|X2=1393|Y2=443|X3=1387|Y3=449|X4=1393|Y4=455|X5=1387|Y5=461|X6=1393|Y6=467|X7=1390|Y7=470
|RECORD=41|OwnerIndex=699|IndexInSheet=3|OwnerPartId=-1|Location.X=1386|Location.Y=482|Color=8388608|FontID=1|IsHidden=T|Text=8-Jun-2000|Name=Published
|RECORD=41|OwnerIndex=699|IndexInSheet=4|OwnerPartId=-1|Location.X=1386|Location.Y=482|Color=8388608|FontID=1|IsHidden=T|Text=29-May-2009|Name=LatestRevisionDate
|RECORD=41|OwnerIndex=699|IndexInSheet=5|OwnerPartId=-1|Location.X=1386|Location.Y=482|Color=8388608|FontID=1|IsHidden=T|Text=IPC-7351 Footprint Added.|Name=LatestRevisionNote
|RECORD=41|OwnerIndex=699|IndexInSheet=6|OwnerPartId=-1|Location.X=1386|Location.Y=482|Color=8388608|FontID=1|IsHidden=T|Text=J1-0603|Name=PackageReference
|RECORD=41|OwnerIndex=699|IndexInSheet=7|OwnerPartId=-1|Location.X=1386|Location.Y=482|Color=8388608|FontID=1|IsHidden=T|Text=Altium Limited|Name=Publisher
|RECORD=41|OwnerIndex=699|IndexInSheet=8|OwnerPartId=-1|Location.X=1386|Location.Y=482|Color=8388608|FontID=1|IsHidden=T|Text=Chip Resistor|Name=PackageDescription
|RECORD=41|OwnerIndex=699|IndexInSheet=9|OwnerPartId=-1|Location.X=1394|Location.Y=441|Color=8388608|FontID=1|Text=0 Ohm|Name=Value
|RECORD=34|OwnerIndex=699|IndexInSheet=-1|OwnerPartId=-1|Location.X=1394|Location.Y=461|Color=8388608|FontID=1|Text=R32|Name=Designator|ReadOnlyState=1
|RECORD=41|OwnerIndex=699|IndexInSheet=-1|OwnerPartId=-1|Location.X=1394|Location.Y=451|Color=8388608|FontID=1|Text=GPS1|Name=Comment
|RECORD=44|OwnerIndex=699
|RECORD=45|OwnerIndex=714|IndexInSheet=-1|Description=Chip Resistor, Body 1.6x0.8mm, IPC High Density|UseComponentLibrary=T|ModelName=J1-0603|ModelType=PCBLIB|DatafileCount=1|ModelDatafileEntity0=J1-0603|ModelDatafileKind0=PCBLib|IsCurrent=T|DatalinksLocked=T|DatabaseDatalinksLocked=T|IntegratedModel=T|DatabaseModel=T
|RECORD=46|OwnerIndex=715
|RECORD=48|OwnerIndex=715
|RECORD=45|OwnerIndex=714|IndexInSheet=-1|Description=Chip Resistor, Body 3.2x2.5mm, IPC High Density|UseComponentLibrary=T|ModelName=14-1210|ModelType=PCBLIB|DatafileCount=1|ModelDatafileEntity0=14-1210|ModelDatafileKind0=PCBLib|DatalinksLocked=T|DatabaseDatalinksLocked=T|IntegratedModel=T|DatabaseModel=T
|RECORD=46|OwnerIndex=718
|RECORD=48|OwnerIndex=718
|RECORD=45|OwnerIndex=714|IndexInSheet=-1|Description=Chip Resistor, Body 5.0x2.5mm, IPC High Density|UseComponentLibrary=T|ModelName=12Z-2010|ModelType=PCBLIB|DatafileCount=1|ModelDatafileEntity0=12Z-2010|ModelDatafileKind0=PCBLib|DatalinksLocked=T|DatabaseDatalinksLocked=T|IntegratedModel=T|DatabaseModel=T
|RECORD=46|OwnerIndex=721
|RECORD=48|OwnerIndex=721
|RECORD=45|OwnerIndex=714|IndexInSheet=-1|Description=Chip Resistor, Body 6.3x3.2mm, IPC High Density|UseComponentLibrary=T|ModelName=RESC6332|ModelType=PCBLIB|DatafileCount=1|ModelDatafileEntity0=RESC6332|ModelDatafileKind0=PCBLib|DatalinksLocked=T|DatabaseDatalinksLocked=T|IntegratedModel=T|DatabaseModel=T
|RECORD=46|OwnerIndex=724
|RECORD=48|OwnerIndex=724
|RECORD=45|OwnerIndex=714|IndexInSheet=-1|Description=Resistor|UseComponentLibrary=T|ModelName=RESISTOR|ModelType=SIM|IsCurrent=T|DatalinksLocked=T|DatabaseDatalinksLocked=T|IntegratedModel=T|DatabaseModel=T
|RECORD=46|OwnerIndex=727
|RECORD=48|OwnerIndex=727
|RECORD=41|OwnerIndex=729|IndexInSheet=-1|OwnerPartId=-1|Color=8388608|FontID=1|Text=R|Name=Spice Prefix
|RECORD=41|OwnerIndex=729|IndexInSheet=-1|OwnerPartId=-1|Color=8388608|FontID=1|Text=@DESIGNATOR %1 %2 @VALUE|Name=Netlist
|RECORD=41|OwnerIndex=729|IndexInSheet=-1|OwnerPartId=-1|Color=8388608|FontID=1|Text=General|Name=Kind
|RECORD=41|OwnerIndex=729|IndexInSheet=-1|OwnerPartId=-1|Color=8388608|FontID=1|Text=Resistor|Name=SubKind
|RECORD=45|OwnerIndex=714|IndexInSheet=-1|UseComponentLibrary=T|ModelName=Res|ModelType=SI|IsCurrent=T|DatalinksLocked=T|DatabaseDatalinksLocked=T|IntegratedModel=T|DatabaseModel=T
|RECORD=46|OwnerIndex=734
|RECORD=48|OwnerIndex=734
|RECORD=41|OwnerIndex=736|IndexInSheet=-1|OwnerPartId=-1|Color=8388608|FontID=1|Text=Resistor|Name=Type
|RECORD=41|OwnerIndex=736|IndexInSheet=-1|OwnerPartId=-1|Color=8388608|FontID=1|Name=Tech
|RECORD=1|LibReference=RES|ComponentDescription=ERJ-3EKF2000V|PartCount=2|DisplayModeCount=2|IndexInSheet=72|OwnerPartId=-1|Location.X=330|Location.Y=650|Orientation=1|CurrentPartId=1|SourceLibraryName=Altium Content Vault|TargetFileName=*|AreaColor=11599871|Color=128|PartIDLocked=F|DesignItemId=CMP-2000-00316-1|AllPinCount=2
|RECORD=2|OwnerIndex=739|OwnerPartId=1|OwnerPartDisplayMode=1|FormalType=1|Electrical=4|PinConglomerate=33|PinLength=10|Location.X=340|Location.Y=670|Name=2|Designator=2|PinPropagationDelay=0.000000E+000
|RECORD=2|OwnerIndex=739|OwnerPartId=1|OwnerPartDisplayMode=1|FormalType=1|Electrical=4|PinConglomerate=35|PinLength=10|Location.X=340|Location.Y=650|Name=1|Designator=1|PinPropagationDelay=0.000000E+000
|RECORD=14|OwnerIndex=739|IsNotAccesible=T|IndexInSheet=2|OwnerPartId=1|OwnerPartDisplayMode=1|Location.X=336|Location.Y=650|Corner.X=344|Corner.Y=670|LineWidth=1|Color=16711680|AreaColor=11599871
|RECORD=2|OwnerIndex=739|OwnerPartId=1|FormalType=1|Electrical=4|PinConglomerate=33|PinLength=10|Location.X=340|Location.Y=670|Name=2|Designator=2|PinPropagationDelay=0.000000E+000
|RECORD=2|OwnerIndex=739|OwnerPartId=1|FormalType=1|Electrical=4|PinConglomerate=35|PinLength=10|Location.X=340|Location.Y=650|Name=1|Designator=1|PinPropagationDelay=0.000000E+000
|RECORD=6|OwnerIndex=739|IsNotAccesible=T|IndexInSheet=5|OwnerPartId=1|LineWidth=1|Color=16711680|LocationCount=10|X1=340|Y1=670|X2=340|Y2=666|X3=342|Y3=665|X4=338|Y4=663|X5=342|Y5=661|X6=338|Y6=659|X7=342|Y7=657|X8=338|Y8=655|X9=340|Y9=654|X10=340|Y10=650
|RECORD=41|OwnerIndex=739|IndexInSheet=6|OwnerPartId=-1|Location.X=337|Location.Y=682|Color=8388608|FontID=1|IsHidden=T|Text=Panasonic|Name=Manufacturer
|RECORD=41|OwnerIndex=739|IndexInSheet=7|OwnerPartId=-1|Location.X=337|Location.Y=682|Color=8388608|FontID=1|IsHidden=T|Text=ERJ-3EKF2000V|Name=Part Number
|RECORD=34|OwnerIndex=739|IndexInSheet=-1|OwnerPartId=-1|Location.X=343|Location.Y=661|Color=8388608|FontID=1|Text=R16|Name=Designator|ReadOnlyState=1
|RECORD=41|OwnerIndex=739|IndexInSheet=-1|OwnerPartId=-1|Location.X=343|Location.Y=651|Color=8388608|FontID=1|Text=200 OHM|Name=Comment
|RECORD=44|OwnerIndex=739
|RECORD=45|OwnerIndex=754|IndexInSheet=-1|Description=Chip Resistor, 2-Leads, Body 1.60x0.80mm, IPC Medium Density|UseComponentLibrary=T|ModelName=RESC1608X55X30NL15T15|ModelType=PCBLIB|IsCurrent=T|DatalinksLocked=T|DatabaseDatalinksLocked=T
|RECORD=46|OwnerIndex=755
|RECORD=48|OwnerIndex=755
|RECORD=41|OwnerIndex=757|IndexInSheet=-1|OwnerPartId=-1|Color=8388608|FontID=1|Text=2D|Name=Available Preview Images
|RECORD=45|OwnerIndex=754|IndexInSheet=-1|Description=Chip Resistor, 2-Leads, Body 1.60x0.80mm, IPC Low Density|UseComponentLibrary=T|ModelName=RESC1608X55X30ML15T15|ModelType=PCBLIB|DatalinksLocked=T|DatabaseDatalinksLocked=T
|RECORD=46|OwnerIndex=759
|RECORD=48|OwnerIndex=759
|RECORD=41|OwnerIndex=761|IndexInSheet=-1|OwnerPartId=-1|Color=8388608|FontID=1|Text=2D|Name=Available Preview Images
|RECORD=45|OwnerIndex=754|IndexInSheet=-1|Description=Chip Resistor, 2-Leads, Body 1.60x0.80mm, IPC High Density|UseComponentLibrary=T|ModelName=RESC1608X55X30LL15T15|ModelType=PCBLIB|DatalinksLocked=T|DatabaseDatalinksLocked=T
|RECORD=46|OwnerIndex=763
|RECORD=48|OwnerIndex=763
|RECORD=41|OwnerIndex=765|IndexInSheet=-1|OwnerPartId=-1|Color=8388608|FontID=1|Text=2D|Name=Available Preview Images
|RECORD=1|LibReference=RES|ComponentDescription=ERJ-3EKF2000V|PartCount=2|DisplayModeCount=2|IndexInSheet=73|OwnerPartId=-1|Location.X=430|Location.Y=650|Orientation=1|CurrentPartId=1|SourceLibraryName=Altium Content Vault|TargetFileName=*|AreaColor=11599871|Color=128|PartIDLocked=F|DesignItemId=CMP-2000-00316-1|AllPinCount=2
|RECORD=2|OwnerIndex=767|OwnerPartId=1|OwnerPartDisplayMode=1|FormalType=1|Electrical=4|PinConglomerate=33|PinLength=10|Location.X=440|Location.Y=670|Name=2|Designator=2|PinPropagationDelay=0.000000E+000
|RECORD=2|OwnerIndex=767|OwnerPartId=1|OwnerPartDisplayMode=1|FormalType=1|Electrical=4|PinConglomerate=35|PinLength=10|Location.X=440|Location.Y=650|Name=1|Designator=1|PinPropagationDelay=0.000000E+000
|RECORD=14|OwnerIndex=767|IsNotAccesible=T|IndexInSheet=2|OwnerPartId=1|OwnerPartDisplayMode=1|Location.X=436|Location.Y=650|Corner.X=444|Corner.Y=670|LineWidth=1|Color=16711680|AreaColor=11599871
|RECORD=2|OwnerIndex=767|OwnerPartId=1|FormalType=1|Electrical=4|PinConglomerate=33|PinLength=10|Location.X=440|Location.Y=670|Name=2|Designator=2|PinPropagationDelay=0.000000E+000
|RECORD=2|OwnerIndex=767|OwnerPartId=1|FormalType=1|Electrical=4|PinConglomerate=35|PinLength=10|Location.X=440|Location.Y=650|Name=1|Designator=1|PinPropagationDelay=0.000000E+000
|RECORD=6|OwnerIndex=767|IsNotAccesible=T|IndexInSheet=5|OwnerPartId=1|LineWidth=1|Color=16711680|LocationCount=10|X1=440|Y1=670|X2=440|Y2=666|X3=442|Y3=665|X4=438|Y4=663|X5=442|Y5=661|X6=438|Y6=659|X7=442|Y7=657|X8=438|Y8=655|X9=440|Y9=654|X10=440|Y10=650
|RECORD=41|OwnerIndex=767|IndexInSheet=6|OwnerPartId=-1|Location.X=437|Location.Y=682|Color=8388608|FontID=1|IsHidden=T|Text=Panasonic|Name=Manufacturer
|RECORD=41|OwnerIndex=767|IndexInSheet=7|OwnerPartId=-1|Location.X=437|Location.Y=682|Color=8388608|FontID=1|IsHidden=T|Text=ERJ-3EKF2000V|Name=Part Number
|RECORD=34|OwnerIndex=767|IndexInSheet=-1|OwnerPartId=-1|Location.X=443|Location.Y=661|Color=8388608|FontID=1|Text=R28|Name=Designator|ReadOnlyState=1
|RECORD=41|OwnerIndex=767|IndexInSheet=-1|OwnerPartId=-1|Location.X=443|Location.Y=651|Color=8388608|FontID=1|Text=200 OHM|Name=Comment
|RECORD=44|OwnerIndex=767
|RECORD=45|OwnerIndex=782|IndexInSheet=-1|Description=Chip Resistor, 2-Leads, Body 1.60x0.80mm, IPC Medium Density|UseComponentLibrary=T|ModelName=RESC1608X55X30NL15T15|ModelType=PCBLIB|IsCurrent=T|DatalinksLocked=T|DatabaseDatalinksLocked=T
|RECORD=46|OwnerIndex=783
|RECORD=48|OwnerIndex=783
|RECORD=41|OwnerIndex=785|IndexInSheet=-1|OwnerPartId=-1|Color=8388608|FontID=1|Text=2D|Name=Available Preview Images
|RECORD=45|OwnerIndex=782|IndexInSheet=-1|Description=Chip Resistor, 2-Leads, Body 1.60x0.80mm, IPC Low Density|UseComponentLibrary=T|ModelName=RESC1608X55X30ML15T15|ModelType=PCBLIB|DatalinksLocked=T|DatabaseDatalinksLocked=T
|RECORD=46|OwnerIndex=787
|RECORD=48|OwnerIndex=787
|RECORD=41|OwnerIndex=789|IndexInSheet=-1|OwnerPartId=-1|Color=8388608|FontID=1|Text=2D|Name=Available Preview Images
|RECORD=45|OwnerIndex=782|IndexInSheet=-1|Description=Chip Resistor, 2-Leads, Body 1.60x0.80mm, IPC High Density|UseComponentLibrary=T|ModelName=RESC1608X55X30LL15T15|ModelType=PCBLIB|DatalinksLocked=T|DatabaseDatalinksLocked=T
|RECORD=46|OwnerIndex=791
|RECORD=48|OwnerIndex=791
|RECORD=41|OwnerIndex=793|IndexInSheet=-1|OwnerPartId=-1|Color=8388608|FontID=1|Text=2D|Name=Available Preview Images
|RECORD=1|LibReference=RES|ComponentDescription=ERJ-3EKF2000V|PartCount=2|DisplayModeCount=2|IndexInSheet=74|OwnerPartId=-1|Location.X=530|Location.Y=650|Orientation=1|CurrentPartId=1|SourceLibraryName=Altium Content Vault|TargetFileName=*|AreaColor=11599871|Color=128|PartIDLocked=F|DesignItemId=CMP-2000-00316-1|AllPinCount=2
|RECORD=2|OwnerIndex=795|OwnerPartId=1|OwnerPartDisplayMode=1|FormalType=1|Electrical=4|PinConglomerate=33|PinLength=10|Location.X=540|Location.Y=670|Name=2|Designator=2|PinPropagationDelay=0.000000E+000
|RECORD=2|OwnerIndex=795|OwnerPartId=1|OwnerPartDisplayMode=1|FormalType=1|Electrical=4|PinConglomerate=35|PinLength=10|Location.X=540|Location.Y=650|Name=1|Designator=1|PinPropagationDelay=0.000000E+000
|RECORD=14|OwnerIndex=795|IsNotAccesible=T|IndexInSheet=2|OwnerPartId=1|OwnerPartDisplayMode=1|Location.X=536|Location.Y=650|Corner.X=544|Corner.Y=670|LineWidth=1|Color=16711680|AreaColor=11599871
|RECORD=2|OwnerIndex=795|OwnerPartId=1|FormalType=1|Electrical=4|PinConglomerate=33|PinLength=10|Location.X=540|Location.Y=670|Name=2|Designator=2|PinPropagationDelay=0.000000E+000
|RECORD=2|OwnerIndex=795|OwnerPartId=1|FormalType=1|Electrical=4|PinConglomerate=35|PinLength=10|Location.X=540|Location.Y=650|Name=1|Designator=1|PinPropagationDelay=0.000000E+000
|RECORD=6|OwnerIndex=795|IsNotAccesible=T|IndexInSheet=5|OwnerPartId=1|LineWidth=1|Color=16711680|LocationCount=10|X1=540|Y1=670|X2=540|Y2=666|X3=542|Y3=665|X4=538|Y4=663|X5=542|Y5=661|X6=538|Y6=659|X7=542|Y7=657|X8=538|Y8=655|X9=540|Y9=654|X10=540|Y10=650
|RECORD=41|OwnerIndex=795|IndexInSheet=6|OwnerPartId=-1|Location.X=537|Location.Y=682|Color=8388608|FontID=1|IsHidden=T|Text=Panasonic|Name=Manufacturer
|RECORD=41|OwnerIndex=795|IndexInSheet=7|OwnerPartId=-1|Location.X=537|Location.Y=682|Color=8388608|FontID=1|IsHidden=T|Text=ERJ-3EKF2000V|Name=Part Number
|RECORD=34|OwnerIndex=795|IndexInSheet=-1|OwnerPartId=-1|Location.X=543|Location.Y=661|Color=8388608|FontID=1|Text=R29|Name=Designator|ReadOnlyState=1
|RECORD=41|OwnerIndex=795|IndexInSheet=-1|OwnerPartId=-1|Location.X=543|Location.Y=651|Color=8388608|FontID=1|Text=200 OHM|Name=Comment
|RECORD=44|OwnerIndex=795
|RECORD=45|OwnerIndex=810|IndexInSheet=-1|Description=Chip Resistor, 2-Leads, Body 1.60x0.80mm, IPC Medium Density|UseComponentLibrary=T|ModelName=RESC1608X55X30NL15T15|ModelType=PCBLIB|IsCurrent=T|DatalinksLocked=T|DatabaseDatalinksLocked=T
|RECORD=46|OwnerIndex=811
|RECORD=48|OwnerIndex=811
|RECORD=41|OwnerIndex=813|IndexInSheet=-1|OwnerPartId=-1|Color=8388608|FontID=1|Text=2D|Name=Available Preview Images
|RECORD=45|OwnerIndex=810|IndexInSheet=-1|Description=Chip Resistor, 2-Leads, Body 1.60x0.80mm, IPC Low Density|UseComponentLibrary=T|ModelName=RESC1608X55X30ML15T15|ModelType=PCBLIB|DatalinksLocked=T|DatabaseDatalinksLocked=T
|RECORD=46|OwnerIndex=815
|RECORD=48|OwnerIndex=815
|RECORD=41|OwnerIndex=817|IndexInSheet=-1|OwnerPartId=-1|Color=8388608|FontID=1|Text=2D|Name=Available Preview Images
|RECORD=45|OwnerIndex=810|IndexInSheet=-1|Description=Chip Resistor, 2-Leads, Body 1.60x0.80mm, IPC High Density|UseComponentLibrary=T|ModelName=RESC1608X55X30LL15T15|ModelType=PCBLIB|DatalinksLocked=T|DatabaseDatalinksLocked=T
|RECORD=46|OwnerIndex=819
|RECORD=48|OwnerIndex=819
|RECORD=41|OwnerIndex=821|IndexInSheet=-1|OwnerPartId=-1|Color=8388608|FontID=1|Text=2D|Name=Available Preview Images
|RECORD=1|LibReference=RES|ComponentDescription=ERJ-3EKF2000V|PartCount=2|DisplayModeCount=2|IndexInSheet=75|OwnerPartId=-1|Location.X=630|Location.Y=650|Orientation=1|CurrentPartId=1|SourceLibraryName=Altium Content Vault|TargetFileName=*|AreaColor=11599871|Color=128|PartIDLocked=F|DesignItemId=CMP-2000-00316-1|AllPinCount=2
|RECORD=2|OwnerIndex=823|OwnerPartId=1|OwnerPartDisplayMode=1|FormalType=1|Electrical=4|PinConglomerate=33|PinLength=10|Location.X=640|Location.Y=670|Name=2|Designator=2|PinPropagationDelay=0.000000E+000
|RECORD=2|OwnerIndex=823|OwnerPartId=1|OwnerPartDisplayMode=1|FormalType=1|Electrical=4|PinConglomerate=35|PinLength=10|Location.X=640|Location.Y=650|Name=1|Designator=1|PinPropagationDelay=0.000000E+000
|RECORD=14|OwnerIndex=823|IsNotAccesible=T|IndexInSheet=2|OwnerPartId=1|OwnerPartDisplayMode=1|Location.X=636|Location.Y=650|Corner.X=644|Corner.Y=670|LineWidth=1|Color=16711680|AreaColor=11599871
|RECORD=2|OwnerIndex=823|OwnerPartId=1|FormalType=1|Electrical=4|PinConglomerate=33|PinLength=10|Location.X=640|Location.Y=670|Name=2|Designator=2|PinPropagationDelay=0.000000E+000
|RECORD=2|OwnerIndex=823|OwnerPartId=1|FormalType=1|Electrical=4|PinConglomerate=35|PinLength=10|Location.X=640|Location.Y=650|Name=1|Designator=1|PinPropagationDelay=0.000000E+000
|RECORD=6|OwnerIndex=823|IsNotAccesible=T|IndexInSheet=5|OwnerPartId=1|LineWidth=1|Color=16711680|LocationCount=10|X1=640|Y1=670|X2=640|Y2=666|X3=642|Y3=665|X4=638|Y4=663|X5=642|Y5=661|X6=638|Y6=659|X7=642|Y7=657|X8=638|Y8=655|X9=640|Y9=654|X10=640|Y10=650
|RECORD=41|OwnerIndex=823|IndexInSheet=6|OwnerPartId=-1|Location.X=637|Location.Y=682|Color=8388608|FontID=1|IsHidden=T|Text=Panasonic|Name=Manufacturer
|RECORD=41|OwnerIndex=823|IndexInSheet=7|OwnerPartId=-1|Location.X=637|Location.Y=682|Color=8388608|FontID=1|IsHidden=T|Text=ERJ-3EKF2000V|Name=Part Number
|RECORD=34|OwnerIndex=823|IndexInSheet=-1|OwnerPartId=-1|Location.X=643|Location.Y=661|Color=8388608|FontID=1|Text=R30|Name=Designator|ReadOnlyState=1
|RECORD=41|OwnerIndex=823|IndexInSheet=-1|OwnerPartId=-1|Location.X=643|Location.Y=651|Color=8388608|FontID=1|Text=200 OHM|Name=Comment
|RECORD=44|OwnerIndex=823
|RECORD=45|OwnerIndex=838|IndexInSheet=-1|Description=Chip Resistor, 2-Leads, Body 1.60x0.80mm, IPC Medium Density|UseComponentLibrary=T|ModelName=RESC1608X55X30NL15T15|ModelType=PCBLIB|IsCurrent=T|DatalinksLocked=T|DatabaseDatalinksLocked=T
|RECORD=46|OwnerIndex=839
|RECORD=48|OwnerIndex=839
|RECORD=41|OwnerIndex=841|IndexInSheet=-1|OwnerPartId=-1|Color=8388608|FontID=1|Text=2D|Name=Available Preview Images
|RECORD=45|OwnerIndex=838|IndexInSheet=-1|Description=Chip Resistor, 2-Leads, Body 1.60x0.80mm, IPC Low Density|UseComponentLibrary=T|ModelName=RESC1608X55X30ML15T15|ModelType=PCBLIB|DatalinksLocked=T|DatabaseDatalinksLocked=T
|RECORD=46|OwnerIndex=843
|RECORD=48|OwnerIndex=843
|RECORD=41|OwnerIndex=845|IndexInSheet=-1|OwnerPartId=-1|Color=8388608|FontID=1|Text=2D|Name=Available Preview Images
|RECORD=45|OwnerIndex=838|IndexInSheet=-1|Description=Chip Resistor, 2-Leads, Body 1.60x0.80mm, IPC High Density|UseComponentLibrary=T|ModelName=RESC1608X55X30LL15T15|ModelType=PCBLIB|DatalinksLocked=T|DatabaseDatalinksLocked=T
|RECORD=46|OwnerIndex=847
|RECORD=48|OwnerIndex=847
|RECORD=41|OwnerIndex=849|IndexInSheet=-1|OwnerPartId=-1|Color=8388608|FontID=1|Text=2D|Name=Available Preview Images
|RECORD=17|IndexInSheet=76|OwnerPartId=-1|ShowNetName=T|Location.X=1140|Location.Y=490|Color=255|FontID=1|Text=MAC_FREQ_CTRL|IsCrossSheetConnector=T
|RECORD=17|IndexInSheet=77|OwnerPartId=-1|ShowNetName=T|Location.X=1420|Location.Y=760|Color=255|FontID=1|Text=MAC_PPS_OUT+|IsCrossSheetConnector=T
|RECORD=17|IndexInSheet=78|OwnerPartId=-1|ShowNetName=T|Location.X=1140|Location.Y=750|Color=255|FontID=1|Text=MAC_PPS_IN0+|IsCrossSheetConnector=T
|RECORD=1|LibReference=CN-1P-M-RF3|ComponentDescription=Ultra Miniature Coaxial Connector Jack, 60 V, 50 Ohm, -40 to 90 degC, RoHS, Tape and Reel|PartCount=2|DisplayModeCount=1|IndexInSheet=79|OwnerPartId=-1|Location.X=1050|Location.Y=770|IsMirrored=T|CurrentPartId=1|LibraryPath=*|SourceLibraryName=Altium Content Vault|TargetFileName=*|AreaColor=11599871|Color=128|PartIDLocked=T|DesignItemId=CMP-2000-07505-1|AllPinCount=3
|RECORD=8|OwnerIndex=854|IsNotAccesible=T|OwnerPartId=1|Location.X=1030|Location.Y=750|Radius=20|SecondaryRadius=20|LineWidth=1|Color=16711680|AreaColor=16777215
|RECORD=8|OwnerIndex=854|IsNotAccesible=T|IndexInSheet=1|OwnerPartId=1|Location.X=1030|Location.Y=750|Radius=4|SecondaryRadius=4|LineWidth=1|Color=16711680|AreaColor=16777215
|RECORD=2|OwnerIndex=854|OwnerPartId=1|FormalType=1|Electrical=4|PinConglomerate=51|PinLength=10|Location.X=1040|Location.Y=730|Name=1|Designator=1|PinPropagationDelay=0.000000E+000
|RECORD=2|OwnerIndex=854|OwnerPartId=1|FormalType=1|Electrical=4|PinConglomerate=48|PinLength=10|Location.X=1050|Location.Y=750|Name=2|Designator=2|PinPropagationDelay=0.000000E+000
|RECORD=2|OwnerIndex=854|OwnerPartId=1|FormalType=1|Electrical=4|PinConglomerate=51|PinLength=10|Location.X=1020|Location.Y=730|Name=3|Designator=3|PinPropagationDelay=0.000000E+000
|RECORD=6|OwnerIndex=854|IsNotAccesible=T|IndexInSheet=5|OwnerPartId=1|LineWidth=1|Color=16711680|LocationCount=5|X1=1050|Y1=730|X2=1050|Y2=770|X3=1010|Y3=770|X4=1010|Y4=730|X5=1050|Y5=730
|RECORD=6|OwnerIndex=854|IsNotAccesible=T|IndexInSheet=6|OwnerPartId=1|LineWidth=1|Color=16711680|LocationCount=2|X1=1050|Y1=750|X2=1034|Y2=750
|RECORD=41|OwnerIndex=854|IndexInSheet=7|OwnerPartId=-1|Location.X=1009|Location.Y=771|Color=8388608|FontID=1|IsHidden=T|Text=Straight|Name=Orientation|IsMirrored=T
|RECORD=41|OwnerIndex=854|IndexInSheet=8|OwnerPartId=-1|Location.X=1009|Location.Y=771|Color=8388608|FontID=1|IsHidden=T|Text=Female|Name=Gender|IsMirrored=T
|RECORD=41|OwnerIndex=854|IndexInSheet=9|OwnerPartId=-1|Location.X=1009|Location.Y=771|Color=8388608|FontID=1|IsHidden=T|Text=Vertical|Name=PCB Mounting Orientation|IsMirrored=T
|RECORD=41|OwnerIndex=854|IndexInSheet=10|OwnerPartId=-1|Location.X=1009|Location.Y=771|Color=8388608|FontID=1|IsHidden=T|Text=SurfaceMount|Name=Mount|IsMirrored=T
|RECORD=41|OwnerIndex=854|IndexInSheet=11|OwnerPartId=-1|Location.X=1009|Location.Y=771|Color=8388608|FontID=1|IsHidden=T|Text=3mm|Name=Length|IsMirrored=T
|RECORD=41|OwnerIndex=854|IndexInSheet=12|OwnerPartId=-1|Location.X=1009|Location.Y=771|Color=8388608|FontID=1|IsHidden=T|Text=TapeandReel|Name=Packaging|IsMirrored=T
|RECORD=41|OwnerIndex=854|IndexInSheet=13|OwnerPartId=-1|Location.X=1009|Location.Y=771|Color=8388608|FontID=1|IsHidden=T|Text=Jack|Name=Connector Type|IsMirrored=T
|RECORD=41|OwnerIndex=854|IndexInSheet=14|OwnerPartId=-1|Location.X=1009|Location.Y=771|Color=8388608|FontID=1|IsHidden=T|Text=LeadFree|Name=Lead Free|IsMirrored=T
|RECORD=41|OwnerIndex=854|IndexInSheet=15|OwnerPartId=-1|Location.X=1009|Location.Y=771|Color=8388608|FontID=1|IsHidden=T|Text=1|Name=Package Quantity|IsMirrored=T
|RECORD=41|OwnerIndex=854|IndexInSheet=16|OwnerPartId=-1|Location.X=1009|Location.Y=771|Color=8388608|FontID=1|IsHidden=T|Text=SMD/SMT|Name=Termination|IsMirrored=T
|RECORD=41|OwnerIndex=854|IndexInSheet=17|OwnerPartId=-1|Location.X=1009|Location.Y=771|Color=8388608|FontID=1|IsHidden=T|Text=CopperAlloy|Name=Contact Material|IsMirrored=T
|RECORD=41|OwnerIndex=854|IndexInSheet=18|OwnerPartId=-1|Location.X=1009|Location.Y=771|Color=8388608|FontID=1|IsHidden=T|Text=Pull|Name=Fastening Type|IsMirrored=T
|RECORD=41|OwnerIndex=854|IndexInSheet=19|OwnerPartId=-1|Location.X=1009|Location.Y=771|Color=8388608|FontID=1|IsHidden=T|Text=true|Name=RoHSCompliant|IsMirrored=T
|RECORD=41|OwnerIndex=854|IndexInSheet=20|OwnerPartId=-1|Location.X=1009|Location.Y=771|Color=8388608|FontID=1|IsHidden=T|Text=LiquidCrystalPolymer|Name=Body Material|IsMirrored=T
|RECORD=41|OwnerIndex=854|IndexInSheet=21|OwnerPartId=-1|Location.X=1009|Location.Y=771|Color=8388608|FontID=1|IsHidden=T|Text=SMD/SMT|Name=Case\/Package|IsMirrored=T
|RECORD=41|OwnerIndex=854|IndexInSheet=22|OwnerPartId=-1|Location.X=1009|Location.Y=771|Color=8388608|FontID=1|IsHidden=T|Text=90degC|Name=Max Operating Temperature|IsMirrored=T
|RECORD=41|OwnerIndex=854|IndexInSheet=23|OwnerPartId=-1|Location.X=1009|Location.Y=771|Color=8388608|FontID=1|IsHidden=T|Text=50Ohm|Name=Impedance|IsMirrored=T
|RECORD=41|OwnerIndex=854|IndexInSheet=24|OwnerPartId=-1|Location.X=1009|Location.Y=771|Color=8388608|FontID=5|IsHidden=T|Text=http://www.te.com/commerce/DocumentDelivery/DDEController?Action=srchrtrv&DocNm=1909763&DocType=Customer+Drawing&DocLang=English|Name=Datasheet URL|IsMirrored=T
|RECORD=41|OwnerIndex=854|IndexInSheet=25|OwnerPartId=-1|Location.X=1009|Location.Y=771|Color=8388608|FontID=1|IsHidden=T|Text=Gold|Name=Contact Plating|IsMirrored=T
|RECORD=41|OwnerIndex=854|IndexInSheet=26|OwnerPartId=-1|Location.X=1009|Location.Y=771|Color=8388608|FontID=1|IsHidden=T|Text=SurfaceMount|Name=Mounting Technology|IsMirrored=T
|RECORD=41|OwnerIndex=854|IndexInSheet=27|OwnerPartId=-1|Location.X=1009|Location.Y=771|Color=8388608|FontID=1|IsHidden=T|Text=6GHz|Name=Max Frequency|IsMirrored=T
|RECORD=41|OwnerIndex=854|IndexInSheet=28|OwnerPartId=-1|Location.X=1009|Location.Y=771|Color=8388608|FontID=1|IsHidden=T|Text=TECO-1909763-1|Name=Package Reference|IsMirrored=T
|RECORD=41|OwnerIndex=854|IndexInSheet=29|OwnerPartId=-1|Location.X=1009|Location.Y=771|Color=8388608|FontID=1|IsHidden=T|Text=Thermoplastic|Name=Insulation Material|IsMirrored=T
|RECORD=41|OwnerIndex=854|IndexInSheet=30|OwnerPartId=-1|Location.X=1009|Location.Y=771|Color=8388608|FontID=1|IsHidden=T|Text=-40degC|Name=Min Operating Temperature|IsMirrored=T
|RECORD=41|OwnerIndex=854|IndexInSheet=31|OwnerPartId=-1|Location.X=1009|Location.Y=771|Color=8388608|FontID=5|IsHidden=T|Text=http://www.te.com/|Name=Manufacturer URL|IsMirrored=T
|RECORD=41|OwnerIndex=854|IndexInSheet=32|OwnerPartId=-1|Location.X=1009|Location.Y=771|Color=8388608|FontID=1|IsHidden=T|Text=Gold|Name=Body Plating|IsMirrored=T
|RECORD=41|OwnerIndex=854|IndexInSheet=33|OwnerPartId=-1|Location.X=1009|Location.Y=771|Color=8388608|FontID=1|IsHidden=T|Text=Polymer|Name=Dielectric Material|IsMirrored=T
|RECORD=41|OwnerIndex=854|IndexInSheet=34|OwnerPartId=-1|Location.X=1009|Location.Y=771|Color=8388608|FontID=1|IsHidden=T|Text=TE Connectivity|Name=Manufacturer|IsMirrored=T
|RECORD=41|OwnerIndex=854|IndexInSheet=35|OwnerPartId=-1|Location.X=1009|Location.Y=771|Color=8388608|FontID=1|IsHidden=T|Text=Compliant|Name=ELV|IsMirrored=T
|RECORD=41|OwnerIndex=854|IndexInSheet=36|OwnerPartId=-1|Location.X=1009|Location.Y=771|Color=8388608|FontID=1|IsHidden=T|Text=Rev. B2, 11/2015|Name=Datasheet Version|IsMirrored=T
|RECORD=41|OwnerIndex=854|IndexInSheet=37|OwnerPartId=-1|Location.X=1009|Location.Y=771|Color=8388608|FontID=1|IsHidden=T|Text=No|Name=Radiation Hardening|IsMirrored=T
|RECORD=41|OwnerIndex=854|IndexInSheet=38|OwnerPartId=-1|Location.X=1009|Location.Y=771|Color=8388608|FontID=1|IsHidden=T|Text=3-Pin Surface Mount Device, Body 2.6 x 2.6 mm|Name=Package Description|IsMirrored=T
|RECORD=41|OwnerIndex=854|IndexInSheet=39|OwnerPartId=-1|Location.X=1009|Location.Y=771|Color=8388608|FontID=1|IsHidden=T|Text=Beige|Name=Housing Colour|IsMirrored=T
|RECORD=34|OwnerIndex=854|IndexInSheet=-1|OwnerPartId=-1|Location.X=1010|Location.Y=780|Color=8388608|FontID=1|Text=J6|Name=Designator|ReadOnlyState=1|IsMirrored=T
|RECORD=41|OwnerIndex=854|IndexInSheet=-1|OwnerPartId=-1|Location.X=1010|Location.Y=770|Color=8388608|FontID=1|Text=1909763-1|Name=Comment|IsMirrored=T
|RECORD=44|OwnerIndex=854
|RECORD=45|OwnerIndex=900|IndexInSheet=-1|Description=SMD, 3-Leads, Body 2.6x2.6mm, Height 1.25mm|UseComponentLibrary=T|ModelName=TECO-1909763-1_V|ModelType=PCBLIB|IsCurrent=T|DatalinksLocked=T|DatabaseDatalinksLocked=T
|RECORD=46|OwnerIndex=901
|RECORD=48|OwnerIndex=901
|RECORD=41|OwnerIndex=903|IndexInSheet=-1|OwnerPartId=-1|Color=8388608|FontID=1|Text=2D|Name=Available Preview Images
|RECORD=1|LibReference=CN-S-4F-RF5|ComponentDescription=Coaxial connector, 50 Ohm, -65 to 165 degC, 5-Pin THD, RoHS, Bulk|PartCount=2|DisplayModeCount=1|IndexInSheet=80|OwnerPartId=-1|Location.X=1050|Location.Y=680|IsMirrored=T|CurrentPartId=1|LibraryPath=*|SourceLibraryName=Altium Content Vault|TargetFileName=*|AreaColor=11599871|Color=128|PartIDLocked=T|DesignItemId=CMP-2000-05705-1|AllPinCount=5
|RECORD=2|OwnerIndex=905|OwnerPartId=1|FormalType=1|Electrical=4|PinConglomerate=51|PinLength=10|Location.X=1010|Location.Y=640|Name=5|Designator=5|SwapIDPart=Ž&Ž1|PinPropagationDelay=0.000000E+000
|RECORD=8|OwnerIndex=905|IsNotAccesible=T|IndexInSheet=1|OwnerPartId=1|Location.X=1030|Location.Y=660|Radius=20|SecondaryRadius=20|LineWidth=1|Color=16711680|AreaColor=16777215
|RECORD=8|OwnerIndex=905|IsNotAccesible=T|IndexInSheet=2|OwnerPartId=1|Location.X=1030|Location.Y=660|Radius=4|SecondaryRadius=4|LineWidth=1|Color=16711680|AreaColor=16777215
|RECORD=2|OwnerIndex=905|OwnerPartId=1|FormalType=1|Electrical=4|PinConglomerate=48|PinLength=10|Location.X=1050|Location.Y=660|Name=1|Designator=1|PinPropagationDelay=0.000000E+000
|RECORD=2|OwnerIndex=905|OwnerPartId=1|FormalType=1|Electrical=4|PinConglomerate=51|PinLength=10|Location.X=1040|Location.Y=640|Name=2|Designator=2|PinPropagationDelay=0.000000E+000
|RECORD=2|OwnerIndex=905|OwnerPartId=1|FormalType=1|Electrical=4|PinConglomerate=51|PinLength=10|Location.X=1030|Location.Y=640|Name=3|Designator=3|PinPropagationDelay=0.000000E+000
|RECORD=2|OwnerIndex=905|OwnerPartId=1|FormalType=1|Electrical=4|PinConglomerate=51|PinLength=10|Location.X=1020|Location.Y=640|Name=4|Designator=4|PinPropagationDelay=0.000000E+000
|RECORD=6|OwnerIndex=905|IsNotAccesible=T|IndexInSheet=7|OwnerPartId=1|LineWidth=1|Color=16711680|LocationCount=5|X1=1050|Y1=640|X2=1050|Y2=680|X3=1010|Y3=680|X4=1010|Y4=640|X5=1050|Y5=640
|RECORD=6|OwnerIndex=905|IsNotAccesible=T|IndexInSheet=8|OwnerPartId=1|LineWidth=1|Color=16711680|LocationCount=2|X1=1050|Y1=660|X2=1034|Y2=660
|RECORD=41|OwnerIndex=905|IndexInSheet=9|OwnerPartId=-1|Location.X=1007|Location.Y=681|Color=8388608|FontID=1|IsHidden=T|Text=ThroughHole|Name=Mounting Technology|IsMirrored=T
|RECORD=41|OwnerIndex=905|IndexInSheet=10|OwnerPartId=-1|Location.X=1007|Location.Y=681|Color=8388608|FontID=1|IsHidden=T|Text=ThroughHole,RightAngle|Name=Mounting Type|IsMirrored=T
|RECORD=41|OwnerIndex=905|IndexInSheet=11|OwnerPartId=-1|Location.X=1007|Location.Y=681|Color=8388608|FontID=1|IsHidden=T|Text=-|Name=Cable Group|IsMirrored=T
|RECORD=41|OwnerIndex=905|IndexInSheet=12|OwnerPartId=-1|Location.X=1007|Location.Y=681|Color=8388608|FontID=1|IsHidden=T|Text=901-143-6RFXMountingHole|Name=Catalog Drawings|IsMirrored=T
|RECORD=41|OwnerIndex=905|IndexInSheet=13|OwnerPartId=-1|Location.X=1007|Location.Y=681|Color=8388608|FontID=1|IsHidden=T|Text=901-143-6RFX.igs|Name=3D Model|IsMirrored=T
|RECORD=41|OwnerIndex=905|IndexInSheet=14|OwnerPartId=-1|Location.X=1007|Location.Y=681|Color=8388608|FontID=1|IsHidden=T|Text=-|Name=Series|IsMirrored=T
|RECORD=41|OwnerIndex=905|IndexInSheet=15|OwnerPartId=-1|Location.X=1007|Location.Y=681|Color=8388608|FontID=1|IsHidden=T|Text=5-Pin Through Hole Device, Body 7 x 7 mm, Pitch 2.54 mm|Name=Package Description|IsMirrored=T
|RECORD=41|OwnerIndex=905|IndexInSheet=16|OwnerPartId=-1|Location.X=1007|Location.Y=681|Color=8388608|FontID=1|IsHidden=T|Text=901-143-6RFX|Name=Package Reference|IsMirrored=T
|RECORD=41|OwnerIndex=905|IndexInSheet=17|OwnerPartId=-1|Location.X=1007|Location.Y=681|Color=8388608|FontID=1|IsHidden=T|Text=Brass|Name=Body Material|IsMirrored=T
|RECORD=41|OwnerIndex=905|IndexInSheet=18|OwnerPartId=-1|Location.X=1007|Location.Y=681|Color=8388608|FontID=1|IsHidden=T|Text=-|Name=Voltage Rating|IsMirrored=T
|RECORD=41|OwnerIndex=905|IndexInSheet=19|OwnerPartId=-1|Location.X=1007|Location.Y=681|Color=8388608|FontID=1|IsHidden=T|Text=1|Name=Standard Package|IsMirrored=T
|RECORD=41|OwnerIndex=905|IndexInSheet=20|OwnerPartId=-1|Location.X=1007|Location.Y=681|Color=8388608|FontID=1|IsHidden=T|Text=Jack,FemaleSocket|Name=Connector Type|IsMirrored=T
|RECORD=41|OwnerIndex=905|IndexInSheet=21|OwnerPartId=-1|Location.X=1007|Location.Y=681|Color=8388608|FontID=1|IsHidden=T|Text=Threaded|Name=Fastening Type|IsMirrored=T
|RECORD=41|OwnerIndex=905|IndexInSheet=22|OwnerPartId=-1|Location.X=1007|Location.Y=681|Color=8388608|FontID=1|IsHidden=T|Text=Gold|Name=Housing Color|IsMirrored=T
|RECORD=41|OwnerIndex=905|IndexInSheet=23|OwnerPartId=-1|Location.X=1007|Location.Y=681|Color=8388608|FontID=1|IsHidden=T|Text=Solder|Name=Shield Termination|IsMirrored=T
|RECORD=41|OwnerIndex=905|IndexInSheet=24|OwnerPartId=-1|Location.X=1007|Location.Y=681|Color=8388608|FontID=1|IsHidden=T|Text=901-143-6-RFX9011436RFXARFX1232|Name=Other Names|IsMirrored=T
|RECORD=41|OwnerIndex=905|IndexInSheet=25|OwnerPartId=-1|Location.X=1007|Location.Y=681|Color=8388608|FontID=5|IsHidden=T|Text=http://www.amphenolrf.com/downloads/dl/file/id/2712/product/3102/901_143_6rfx_customer_drawing.pdf|Name=Datasheet URL|IsMirrored=T
|RECORD=41|OwnerIndex=905|IndexInSheet=26|OwnerPartId=-1|Location.X=1007|Location.Y=681|Color=8388608|FontID=1|IsHidden=T|Text=CoaxialConnectors(RF)|Name=Family|IsMirrored=T
|RECORD=41|OwnerIndex=905|IndexInSheet=27|OwnerPartId=-1|Location.X=1007|Location.Y=681|Color=8388608|FontID=1|IsHidden=T|Text=SMA,RFX|Name=Online Catalog|IsMirrored=T
|RECORD=41|OwnerIndex=905|IndexInSheet=28|OwnerPartId=-1|Location.X=1007|Location.Y=681|Color=8388608|FontID=1|IsHidden=T|Text=18GHz|Name=Frequency - Max|IsMirrored=T
|RECORD=41|OwnerIndex=905|IndexInSheet=29|OwnerPartId=-1|Location.X=1007|Location.Y=681|Color=8388608|FontID=1|IsHidden=T|Text=Solder|Name=Contact Termination|IsMirrored=T
|RECORD=41|OwnerIndex=905|IndexInSheet=30|OwnerPartId=-1|Location.X=1007|Location.Y=681|Color=8388608|FontID=5|IsHidden=T|Text=http://www.amphenol.com/|Name=Manufacturer URL|IsMirrored=T
|RECORD=41|OwnerIndex=905|IndexInSheet=31|OwnerPartId=-1|Location.X=1007|Location.Y=681|Color=8388608|FontID=1|IsHidden=T|Text=Amphenol|Name=Manufacturer|IsMirrored=T
|RECORD=41|OwnerIndex=905|IndexInSheet=32|OwnerPartId=-1|Location.X=1007|Location.Y=681|Color=8388608|FontID=1|IsHidden=T|Text=-65°C~165°C|Name=Operating Temperature|IsMirrored=T
|RECORD=41|OwnerIndex=905|IndexInSheet=33|OwnerPartId=-1|Location.X=1007|Location.Y=681|Color=8388608|FontID=1|IsHidden=T|Text=Connectors,Interconnects|Name=Category|IsMirrored=T
|RECORD=41|OwnerIndex=905|IndexInSheet=34|OwnerPartId=-1|Location.X=1007|Location.Y=681|Color=8388608|FontID=1|IsHidden=T|Text=Bulk|Name=Packaging|IsMirrored=T
|RECORD=41|OwnerIndex=905|IndexInSheet=35|OwnerPartId=-1|Location.X=1007|Location.Y=681|Color=8388608|FontID=1|IsHidden=T|Text=Gold|Name=Body Finish|IsMirrored=T
|RECORD=41|OwnerIndex=905|IndexInSheet=36|OwnerPartId=-1|Location.X=1007|Location.Y=681|Color=8388608|FontID=1|IsHidden=T|Text=Polytetrafluoroethylene(PTFE)|Name=Dielectric Material|IsMirrored=T
|RECORD=41|OwnerIndex=905|IndexInSheet=37|OwnerPartId=-1|Location.X=1007|Location.Y=681|Color=8388608|FontID=1|IsHidden=T|Text=BerylliumCopper|Name=Center Contact Material|IsMirrored=T
|RECORD=41|OwnerIndex=905|IndexInSheet=38|OwnerPartId=-1|Location.X=1007|Location.Y=681|Color=8388608|FontID=1|IsHidden=T|Text=50Ohm|Name=Impedance|IsMirrored=T
|RECORD=41|OwnerIndex=905|IndexInSheet=39|OwnerPartId=-1|Location.X=1007|Location.Y=681|Color=8388608|FontID=1|IsHidden=T|Text=-|Name=Features|IsMirrored=T
|RECORD=41|OwnerIndex=905|IndexInSheet=40|OwnerPartId=-1|Location.X=1007|Location.Y=681|Color=8388608|FontID=1|IsHidden=T|Text=SMA|Name=Connector Style|IsMirrored=T
|RECORD=41|OwnerIndex=905|IndexInSheet=41|OwnerPartId=-1|Location.X=1007|Location.Y=681|Color=8388608|FontID=1|IsHidden=T|Text=Gold|Name=Center Contact Plating|IsMirrored=T
|RECORD=41|OwnerIndex=905|IndexInSheet=42|OwnerPartId=-1|Location.X=1007|Location.Y=681|Color=8388608|FontID=1|IsHidden=T|Text=Rev. C, 06/2010|Name=Datasheet Version|IsMirrored=T
|RECORD=41|OwnerIndex=905|IndexInSheet=43|OwnerPartId=-1|Location.X=1007|Location.Y=681|Color=8388608|FontID=1|IsHidden=T|Text=-|Name=Ingress Protection|IsMirrored=T
|RECORD=34|OwnerIndex=905|IndexInSheet=-1|OwnerPartId=-1|Location.X=1010|Location.Y=690|Color=8388608|FontID=1|Text=J8|Name=Designator|ReadOnlyState=1|IsMirrored=T
|RECORD=41|OwnerIndex=905|IndexInSheet=-1|OwnerPartId=-1|Location.X=1010|Location.Y=680|Color=8388608|FontID=1|Text=901-143-6RFX|Name=Comment|IsMirrored=T
|RECORD=44|OwnerIndex=905
|RECORD=45|OwnerIndex=957|IndexInSheet=-1|Description=THD, 5-Leads, Body 7x7mm, Pitch 2.54mm|UseComponentLibrary=T|ModelName=AMPH-901-143-6RFX_V|ModelType=PCBLIB|IsCurrent=T|DatalinksLocked=T|DatabaseDatalinksLocked=T
|RECORD=46|OwnerIndex=958
|RECORD=48|OwnerIndex=958
|RECORD=41|OwnerIndex=960|IndexInSheet=-1|OwnerPartId=-1|Color=8388608|FontID=1|Text=2D|Name=Available Preview Images
|RECORD=27|IndexInSheet=81|OwnerPartId=-1|LineWidth=1|Color=8388608|LocationCount=3|X1=300|Y1=420|X2=270|Y2=420|X3=260|Y3=420
|RECORD=27|IndexInSheet=82|OwnerPartId=-1|LineWidth=1|Color=8388608|LocationCount=3|X1=390|Y1=420|X2=400|Y2=420|X3=400|Y3=410
|RECORD=27|IndexInSheet=83|OwnerPartId=-1|LineWidth=1|Color=8388608|LocationCount=3|X1=610|Y1=420|X2=580|Y2=420|X3=570|Y3=420
|RECORD=27|IndexInSheet=84|OwnerPartId=-1|LineWidth=1|Color=8388608|LocationCount=3|X1=710|Y1=410|X2=710|Y2=420|X3=700|Y3=420
|RECORD=27|IndexInSheet=85|OwnerPartId=-1|LineWidth=1|Color=8388608|LocationCount=2|X1=270|Y1=430|X2=270|Y2=420
|RECORD=27|IndexInSheet=86|OwnerPartId=-1|LineWidth=1|Color=8388608|LocationCount=2|X1=340|Y1=690|X2=340|Y2=680
|RECORD=27|IndexInSheet=87|OwnerPartId=-1|LineWidth=1|Color=8388608|LocationCount=2|X1=440|Y1=690|X2=440|Y2=680
|RECORD=27|IndexInSheet=88|OwnerPartId=-1|LineWidth=1|Color=8388608|LocationCount=2|X1=540|Y1=690|X2=540|Y2=680
|RECORD=27|IndexInSheet=89|OwnerPartId=-1|LineWidth=1|Color=8388608|LocationCount=2|X1=580|Y1=430|X2=580|Y2=420
|RECORD=27|IndexInSheet=90|OwnerPartId=-1|LineWidth=1|Color=8388608|LocationCount=2|X1=640|Y1=690|X2=640|Y2=680
|RECORD=27|IndexInSheet=91|OwnerPartId=-1|LineWidth=1|Color=8388608|LocationCount=3|X1=1390|Y1=750|X2=1390|Y2=760|X3=1420|Y3=760
|RECORD=27|IndexInSheet=92|OwnerPartId=-1|LineWidth=1|Color=8388608|LocationCount=6|X1=1010|Y1=370|X2=1010|Y2=310|X3=1020|Y3=310|X4=1030|Y4=310|X5=1040|Y5=310|X6=1090|Y6=310
|RECORD=27|IndexInSheet=93|OwnerPartId=-1|LineWidth=1|Color=8388608|LocationCount=3|X1=1060|Y1=400|X2=1090|Y2=400|X3=1090|Y3=390
|RECORD=27|IndexInSheet=94|OwnerPartId=-1|LineWidth=1|Color=8388608|LocationCount=3|X1=1060|Y1=490|X2=1090|Y2=490|X3=1090|Y3=400
|RECORD=27|IndexInSheet=95|OwnerPartId=-1|LineWidth=1|Color=8388608|LocationCount=3|X1=1060|Y1=660|X2=1090|Y2=660|X3=1090|Y3=650
|RECORD=27|IndexInSheet=96|OwnerPartId=-1|LineWidth=1|Color=8388608|LocationCount=3|X1=1060|Y1=750|X2=1090|Y2=750|X3=1090|Y3=660
|RECORD=27|IndexInSheet=97|OwnerPartId=-1|LineWidth=1|Color=8388608|LocationCount=3|X1=1090|Y1=400|X2=1110|Y2=400|X3=1130|Y3=400
|RECORD=27|IndexInSheet=98|OwnerPartId=-1|LineWidth=1|Color=8388608|LocationCount=3|X1=1090|Y1=660|X2=1110|Y2=660|X3=1130|Y3=660
|RECORD=27|IndexInSheet=99|OwnerPartId=-1|LineWidth=1|Color=8388608|LocationCount=3|X1=1110|Y1=480|X2=1110|Y2=490|X3=1140|Y3=490
|RECORD=27|IndexInSheet=100|OwnerPartId=-1|LineWidth=1|Color=8388608|LocationCount=3|X1=1110|Y1=740|X2=1110|Y2=750|X3=1140|Y3=750
|RECORD=27|IndexInSheet=101|OwnerPartId=-1|LineWidth=1|Color=8388608|LocationCount=3|X1=1340|Y1=400|X2=1370|Y2=400|X3=1370|Y3=390
|RECORD=27|IndexInSheet=102|OwnerPartId=-1|LineWidth=1|Color=8388608|LocationCount=3|X1=1340|Y1=490|X2=1370|Y2=490|X3=1370|Y3=400
|RECORD=27|IndexInSheet=103|OwnerPartId=-1|LineWidth=1|Color=8388608|LocationCount=3|X1=1340|Y1=670|X2=1370|Y2=670|X3=1370|Y3=660
|RECORD=27|IndexInSheet=104|OwnerPartId=-1|LineWidth=1|Color=8388608|LocationCount=3|X1=1340|Y1=760|X2=1370|Y2=760|X3=1370|Y3=670
|RECORD=27|IndexInSheet=105|OwnerPartId=-1|LineWidth=1|Color=8388608|LocationCount=3|X1=1370|Y1=400|X2=1390|Y2=400|X3=1410|Y3=400
|RECORD=27|IndexInSheet=106|OwnerPartId=-1|LineWidth=1|Color=8388608|LocationCount=3|X1=1370|Y1=670|X2=1390|Y2=670|X3=1410|Y3=670
|RECORD=27|IndexInSheet=107|OwnerPartId=-1|LineWidth=1|Color=8388608|LocationCount=2|X1=1090|Y1=310|X2=1090|Y2=300
|RECORD=27|IndexInSheet=108|OwnerPartId=-1|LineWidth=1|Color=8388608|LocationCount=2|X1=1090|Y1=310|X2=1090|Y2=320
|RECORD=27|IndexInSheet=109|OwnerPartId=-1|LineWidth=1|Color=8388608|LocationCount=2|X1=1110|Y1=430|X2=1110|Y2=400
|RECORD=27|IndexInSheet=110|OwnerPartId=-1|LineWidth=1|Color=8388608|LocationCount=2|X1=1110|Y1=690|X2=1110|Y2=660
|RECORD=27|IndexInSheet=111|OwnerPartId=-1|LineWidth=1|Color=8388608|LocationCount=2|X1=1390|Y1=700|X2=1390|Y2=670
|RECORD=27|IndexInSheet=112|OwnerPartId=-1|LineWidth=1|Color=8388608|LocationCount=2|X1=1390|Y1=430|X2=1390|Y2=400
|RECORD=27|IndexInSheet=113|OwnerPartId=-1|LineWidth=1|Color=8388608|LocationCount=3|X1=1390|Y1=480|X2=1390|Y2=490|X3=1430|Y3=490
|RECORD=27|IndexInSheet=114|OwnerPartId=-1|LineWidth=1|Color=8388608|LocationCount=3|X1=340|Y1=640|X2=340|Y2=620|X3=330|Y3=620
|RECORD=27|IndexInSheet=115|OwnerPartId=-1|LineWidth=1|Color=8388608|LocationCount=3|X1=440|Y1=640|X2=440|Y2=620|X3=430|Y3=620
|RECORD=27|IndexInSheet=116|OwnerPartId=-1|LineWidth=1|Color=8388608|LocationCount=3|X1=540|Y1=640|X2=540|Y2=620|X3=530|Y3=620
|RECORD=27|IndexInSheet=117|OwnerPartId=-1|LineWidth=1|Color=8388608|LocationCount=3|X1=640|Y1=640|X2=640|Y2=620|X3=630|Y3=620
|RECORD=1|LibReference=CN-1P-M-RF3|ComponentDescription=Ultra Miniature Coaxial Connector Jack, 60 V, 50 Ohm, -40 to 90 degC, RoHS, Tape and Reel|PartCount=2|DisplayModeCount=1|IndexInSheet=118|OwnerPartId=-1|Location.X=1330|Location.Y=780|IsMirrored=T|CurrentPartId=1|LibraryPath=*|SourceLibraryName=Altium Content Vault|TargetFileName=*|AreaColor=11599871|Color=128|PartIDLocked=T|DesignItemId=CMP-2000-07505-1|AllPinCount=3
|RECORD=8|OwnerIndex=999|IsNotAccesible=T|OwnerPartId=1|Location.X=1310|Location.Y=760|Radius=20|SecondaryRadius=20|LineWidth=1|Color=16711680|AreaColor=16777215
|RECORD=8|OwnerIndex=999|IsNotAccesible=T|IndexInSheet=1|OwnerPartId=1|Location.X=1310|Location.Y=760|Radius=4|SecondaryRadius=4|LineWidth=1|Color=16711680|AreaColor=16777215
|RECORD=2|OwnerIndex=999|OwnerPartId=1|FormalType=1|Electrical=4|PinConglomerate=51|PinLength=10|Location.X=1320|Location.Y=740|Name=1|Designator=1|PinPropagationDelay=0.000000E+000
|RECORD=2|OwnerIndex=999|OwnerPartId=1|FormalType=1|Electrical=4|PinConglomerate=48|PinLength=10|Location.X=1330|Location.Y=760|Name=2|Designator=2|PinPropagationDelay=0.000000E+000
|RECORD=2|OwnerIndex=999|OwnerPartId=1|FormalType=1|Electrical=4|PinConglomerate=51|PinLength=10|Location.X=1300|Location.Y=740|Name=3|Designator=3|PinPropagationDelay=0.000000E+000
|RECORD=6|OwnerIndex=999|IsNotAccesible=T|IndexInSheet=5|OwnerPartId=1|LineWidth=1|Color=16711680|LocationCount=5|X1=1330|Y1=740|X2=1330|Y2=780|X3=1290|Y3=780|X4=1290|Y4=740|X5=1330|Y5=740
|RECORD=6|OwnerIndex=999|IsNotAccesible=T|IndexInSheet=6|OwnerPartId=1|LineWidth=1|Color=16711680|LocationCount=2|X1=1330|Y1=760|X2=1314|Y2=760
|RECORD=41|OwnerIndex=999|IndexInSheet=7|OwnerPartId=-1|Location.X=1289|Location.Y=781|Color=8388608|FontID=1|IsHidden=T|Text=Straight|Name=Orientation|IsMirrored=T
|RECORD=41|OwnerIndex=999|IndexInSheet=8|OwnerPartId=-1|Location.X=1289|Location.Y=781|Color=8388608|FontID=1|IsHidden=T|Text=Female|Name=Gender|IsMirrored=T
|RECORD=41|OwnerIndex=999|IndexInSheet=9|OwnerPartId=-1|Location.X=1289|Location.Y=781|Color=8388608|FontID=1|IsHidden=T|Text=Vertical|Name=PCB Mounting Orientation|IsMirrored=T
|RECORD=41|OwnerIndex=999|IndexInSheet=10|OwnerPartId=-1|Location.X=1289|Location.Y=781|Color=8388608|FontID=1|IsHidden=T|Text=SurfaceMount|Name=Mount|IsMirrored=T
|RECORD=41|OwnerIndex=999|IndexInSheet=11|OwnerPartId=-1|Location.X=1289|Location.Y=781|Color=8388608|FontID=1|IsHidden=T|Text=3mm|Name=Length|IsMirrored=T
|RECORD=41|OwnerIndex=999|IndexInSheet=12|OwnerPartId=-1|Location.X=1289|Location.Y=781|Color=8388608|FontID=1|IsHidden=T|Text=TapeandReel|Name=Packaging|IsMirrored=T
|RECORD=41|OwnerIndex=999|IndexInSheet=13|OwnerPartId=-1|Location.X=1289|Location.Y=781|Color=8388608|FontID=1|IsHidden=T|Text=Jack|Name=Connector Type|IsMirrored=T
|RECORD=41|OwnerIndex=999|IndexInSheet=14|OwnerPartId=-1|Location.X=1289|Location.Y=781|Color=8388608|FontID=1|IsHidden=T|Text=LeadFree|Name=Lead Free|IsMirrored=T
|RECORD=41|OwnerIndex=999|IndexInSheet=15|OwnerPartId=-1|Location.X=1289|Location.Y=781|Color=8388608|FontID=1|IsHidden=T|Text=1|Name=Package Quantity|IsMirrored=T
|RECORD=41|OwnerIndex=999|IndexInSheet=16|OwnerPartId=-1|Location.X=1289|Location.Y=781|Color=8388608|FontID=1|IsHidden=T|Text=SMD/SMT|Name=Termination|IsMirrored=T
|RECORD=41|OwnerIndex=999|IndexInSheet=17|OwnerPartId=-1|Location.X=1289|Location.Y=781|Color=8388608|FontID=1|IsHidden=T|Text=CopperAlloy|Name=Contact Material|IsMirrored=T
|RECORD=41|OwnerIndex=999|IndexInSheet=18|OwnerPartId=-1|Location.X=1289|Location.Y=781|Color=8388608|FontID=1|IsHidden=T|Text=Pull|Name=Fastening Type|IsMirrored=T
|RECORD=41|OwnerIndex=999|IndexInSheet=19|OwnerPartId=-1|Location.X=1289|Location.Y=781|Color=8388608|FontID=1|IsHidden=T|Text=true|Name=RoHSCompliant|IsMirrored=T
|RECORD=41|OwnerIndex=999|IndexInSheet=20|OwnerPartId=-1|Location.X=1289|Location.Y=781|Color=8388608|FontID=1|IsHidden=T|Text=LiquidCrystalPolymer|Name=Body Material|IsMirrored=T
|RECORD=41|OwnerIndex=999|IndexInSheet=21|OwnerPartId=-1|Location.X=1289|Location.Y=781|Color=8388608|FontID=1|IsHidden=T|Text=SMD/SMT|Name=Case\/Package|IsMirrored=T
|RECORD=41|OwnerIndex=999|IndexInSheet=22|OwnerPartId=-1|Location.X=1289|Location.Y=781|Color=8388608|FontID=1|IsHidden=T|Text=90degC|Name=Max Operating Temperature|IsMirrored=T
|RECORD=41|OwnerIndex=999|IndexInSheet=23|OwnerPartId=-1|Location.X=1289|Location.Y=781|Color=8388608|FontID=1|IsHidden=T|Text=50Ohm|Name=Impedance|IsMirrored=T
|RECORD=41|OwnerIndex=999|IndexInSheet=24|OwnerPartId=-1|Location.X=1289|Location.Y=781|Color=8388608|FontID=5|IsHidden=T|Text=http://www.te.com/commerce/DocumentDelivery/DDEController?Action=srchrtrv&DocNm=1909763&DocType=Customer+Drawing&DocLang=English|Name=Datasheet URL|IsMirrored=T
|RECORD=41|OwnerIndex=999|IndexInSheet=25|OwnerPartId=-1|Location.X=1289|Location.Y=781|Color=8388608|FontID=1|IsHidden=T|Text=Gold|Name=Contact Plating|IsMirrored=T
|RECORD=41|OwnerIndex=999|IndexInSheet=26|OwnerPartId=-1|Location.X=1289|Location.Y=781|Color=8388608|FontID=1|IsHidden=T|Text=SurfaceMount|Name=Mounting Technology|IsMirrored=T
|RECORD=41|OwnerIndex=999|IndexInSheet=27|OwnerPartId=-1|Location.X=1289|Location.Y=781|Color=8388608|FontID=1|IsHidden=T|Text=6GHz|Name=Max Frequency|IsMirrored=T
|RECORD=41|OwnerIndex=999|IndexInSheet=28|OwnerPartId=-1|Location.X=1289|Location.Y=781|Color=8388608|FontID=1|IsHidden=T|Text=TECO-1909763-1|Name=Package Reference|IsMirrored=T
|RECORD=41|OwnerIndex=999|IndexInSheet=29|OwnerPartId=-1|Location.X=1289|Location.Y=781|Color=8388608|FontID=1|IsHidden=T|Text=Thermoplastic|Name=Insulation Material|IsMirrored=T
|RECORD=41|OwnerIndex=999|IndexInSheet=30|OwnerPartId=-1|Location.X=1289|Location.Y=781|Color=8388608|FontID=1|IsHidden=T|Text=-40degC|Name=Min Operating Temperature|IsMirrored=T
|RECORD=41|OwnerIndex=999|IndexInSheet=31|OwnerPartId=-1|Location.X=1289|Location.Y=781|Color=8388608|FontID=5|IsHidden=T|Text=http://www.te.com/|Name=Manufacturer URL|IsMirrored=T
|RECORD=41|OwnerIndex=999|IndexInSheet=32|OwnerPartId=-1|Location.X=1289|Location.Y=781|Color=8388608|FontID=1|IsHidden=T|Text=Gold|Name=Body Plating|IsMirrored=T
|RECORD=41|OwnerIndex=999|IndexInSheet=33|OwnerPartId=-1|Location.X=1289|Location.Y=781|Color=8388608|FontID=1|IsHidden=T|Text=Polymer|Name=Dielectric Material|IsMirrored=T
|RECORD=41|OwnerIndex=999|IndexInSheet=34|OwnerPartId=-1|Location.X=1289|Location.Y=781|Color=8388608|FontID=1|IsHidden=T|Text=TE Connectivity|Name=Manufacturer|IsMirrored=T
|RECORD=41|OwnerIndex=999|IndexInSheet=35|OwnerPartId=-1|Location.X=1289|Location.Y=781|Color=8388608|FontID=1|IsHidden=T|Text=Compliant|Name=ELV|IsMirrored=T
|RECORD=41|OwnerIndex=999|IndexInSheet=36|OwnerPartId=-1|Location.X=1289|Location.Y=781|Color=8388608|FontID=1|IsHidden=T|Text=Rev. B2, 11/2015|Name=Datasheet Version|IsMirrored=T
|RECORD=41|OwnerIndex=999|IndexInSheet=37|OwnerPartId=-1|Location.X=1289|Location.Y=781|Color=8388608|FontID=1|IsHidden=T|Text=No|Name=Radiation Hardening|IsMirrored=T
|RECORD=41|OwnerIndex=999|IndexInSheet=38|OwnerPartId=-1|Location.X=1289|Location.Y=781|Color=8388608|FontID=1|IsHidden=T|Text=3-Pin Surface Mount Device, Body 2.6 x 2.6 mm|Name=Package Description|IsMirrored=T
|RECORD=41|OwnerIndex=999|IndexInSheet=39|OwnerPartId=-1|Location.X=1289|Location.Y=781|Color=8388608|FontID=1|IsHidden=T|Text=Beige|Name=Housing Colour|IsMirrored=T
|RECORD=34|OwnerIndex=999|IndexInSheet=-1|OwnerPartId=-1|Location.X=1290|Location.Y=790|Color=8388608|FontID=1|Text=J5|Name=Designator|ReadOnlyState=1|IsMirrored=T
|RECORD=41|OwnerIndex=999|IndexInSheet=-1|OwnerPartId=-1|Location.X=1290|Location.Y=780|Color=8388608|FontID=1|Text=1909763-1|Name=Comment|IsMirrored=T
|RECORD=44|OwnerIndex=999
|RECORD=45|OwnerIndex=1045|IndexInSheet=-1|Description=SMD, 3-Leads, Body 2.6x2.6mm, Height 1.25mm|UseComponentLibrary=T|ModelName=TECO-1909763-1_V|ModelType=PCBLIB|IsCurrent=T|DatalinksLocked=T|DatabaseDatalinksLocked=T
|RECORD=46|OwnerIndex=1046
|RECORD=48|OwnerIndex=1046
|RECORD=41|OwnerIndex=1048|IndexInSheet=-1|OwnerPartId=-1|Color=8388608|FontID=1|Text=2D|Name=Available Preview Images
|RECORD=1|LibReference=CN-S-4F-RF5|ComponentDescription=Coaxial connector, 50 Ohm, -65 to 165 degC, 5-Pin THD, RoHS, Bulk|PartCount=2|DisplayModeCount=1|IndexInSheet=119|OwnerPartId=-1|Location.X=1330|Location.Y=690|IsMirrored=T|CurrentPartId=1|LibraryPath=*|SourceLibraryName=Altium Content Vault|TargetFileName=*|AreaColor=11599871|Color=128|PartIDLocked=T|DesignItemId=CMP-2000-05705-1|AllPinCount=5
|RECORD=2|OwnerIndex=1050|OwnerPartId=1|FormalType=1|Electrical=4|PinConglomerate=51|PinLength=10|Location.X=1290|Location.Y=650|Name=5|Designator=5|SwapIDPart=Ž&Ž1|PinPropagationDelay=0.000000E+000
|RECORD=8|OwnerIndex=1050|IsNotAccesible=T|IndexInSheet=1|OwnerPartId=1|Location.X=1310|Location.Y=670|Radius=20|SecondaryRadius=20|LineWidth=1|Color=16711680|AreaColor=16777215
|RECORD=8|OwnerIndex=1050|IsNotAccesible=T|IndexInSheet=2|OwnerPartId=1|Location.X=1310|Location.Y=670|Radius=4|SecondaryRadius=4|LineWidth=1|Color=16711680|AreaColor=16777215
|RECORD=2|OwnerIndex=1050|OwnerPartId=1|FormalType=1|Electrical=4|PinConglomerate=48|PinLength=10|Location.X=1330|Location.Y=670|Name=1|Designator=1|PinPropagationDelay=0.000000E+000
|RECORD=2|OwnerIndex=1050|OwnerPartId=1|FormalType=1|Electrical=4|PinConglomerate=51|PinLength=10|Location.X=1320|Location.Y=650|Name=2|Designator=2|PinPropagationDelay=0.000000E+000
|RECORD=2|OwnerIndex=1050|OwnerPartId=1|FormalType=1|Electrical=4|PinConglomerate=51|PinLength=10|Location.X=1310|Location.Y=650|Name=3|Designator=3|PinPropagationDelay=0.000000E+000
|RECORD=2|OwnerIndex=1050|OwnerPartId=1|FormalType=1|Electrical=4|PinConglomerate=51|PinLength=10|Location.X=1300|Location.Y=650|Name=4|Designator=4|PinPropagationDelay=0.000000E+000
|RECORD=6|OwnerIndex=1050|IsNotAccesible=T|IndexInSheet=7|OwnerPartId=1|LineWidth=1|Color=16711680|LocationCount=5|X1=1330|Y1=650|X2=1330|Y2=690|X3=1290|Y3=690|X4=1290|Y4=650|X5=1330|Y5=650
|RECORD=6|OwnerIndex=1050|IsNotAccesible=T|IndexInSheet=8|OwnerPartId=1|LineWidth=1|Color=16711680|LocationCount=2|X1=1330|Y1=670|X2=1314|Y2=670
|RECORD=41|OwnerIndex=1050|IndexInSheet=9|OwnerPartId=-1|Location.X=1287|Location.Y=691|Color=8388608|FontID=1|IsHidden=T|Text=ThroughHole|Name=Mounting Technology|IsMirrored=T
|RECORD=41|OwnerIndex=1050|IndexInSheet=10|OwnerPartId=-1|Location.X=1287|Location.Y=691|Color=8388608|FontID=1|IsHidden=T|Text=ThroughHole,RightAngle|Name=Mounting Type|IsMirrored=T
|RECORD=41|OwnerIndex=1050|IndexInSheet=11|OwnerPartId=-1|Location.X=1287|Location.Y=691|Color=8388608|FontID=1|IsHidden=T|Text=-|Name=Cable Group|IsMirrored=T
|RECORD=41|OwnerIndex=1050|IndexInSheet=12|OwnerPartId=-1|Location.X=1287|Location.Y=691|Color=8388608|FontID=1|IsHidden=T|Text=901-143-6RFXMountingHole|Name=Catalog Drawings|IsMirrored=T
|RECORD=41|OwnerIndex=1050|IndexInSheet=13|OwnerPartId=-1|Location.X=1287|Location.Y=691|Color=8388608|FontID=1|IsHidden=T|Text=901-143-6RFX.igs|Name=3D Model|IsMirrored=T
|RECORD=41|OwnerIndex=1050|IndexInSheet=14|OwnerPartId=-1|Location.X=1287|Location.Y=691|Color=8388608|FontID=1|IsHidden=T|Text=-|Name=Series|IsMirrored=T
|RECORD=41|OwnerIndex=1050|IndexInSheet=15|OwnerPartId=-1|Location.X=1287|Location.Y=691|Color=8388608|FontID=1|IsHidden=T|Text=5-Pin Through Hole Device, Body 7 x 7 mm, Pitch 2.54 mm|Name=Package Description|IsMirrored=T
|RECORD=41|OwnerIndex=1050|IndexInSheet=16|OwnerPartId=-1|Location.X=1287|Location.Y=691|Color=8388608|FontID=1|IsHidden=T|Text=901-143-6RFX|Name=Package Reference|IsMirrored=T
|RECORD=41|OwnerIndex=1050|IndexInSheet=17|OwnerPartId=-1|Location.X=1287|Location.Y=691|Color=8388608|FontID=1|IsHidden=T|Text=Brass|Name=Body Material|IsMirrored=T
|RECORD=41|OwnerIndex=1050|IndexInSheet=18|OwnerPartId=-1|Location.X=1287|Location.Y=691|Color=8388608|FontID=1|IsHidden=T|Text=-|Name=Voltage Rating|IsMirrored=T
|RECORD=41|OwnerIndex=1050|IndexInSheet=19|OwnerPartId=-1|Location.X=1287|Location.Y=691|Color=8388608|FontID=1|IsHidden=T|Text=1|Name=Standard Package|IsMirrored=T
|RECORD=41|OwnerIndex=1050|IndexInSheet=20|OwnerPartId=-1|Location.X=1287|Location.Y=691|Color=8388608|FontID=1|IsHidden=T|Text=Jack,FemaleSocket|Name=Connector Type|IsMirrored=T
|RECORD=41|OwnerIndex=1050|IndexInSheet=21|OwnerPartId=-1|Location.X=1287|Location.Y=691|Color=8388608|FontID=1|IsHidden=T|Text=Threaded|Name=Fastening Type|IsMirrored=T
|RECORD=41|OwnerIndex=1050|IndexInSheet=22|OwnerPartId=-1|Location.X=1287|Location.Y=691|Color=8388608|FontID=1|IsHidden=T|Text=Gold|Name=Housing Color|IsMirrored=T
|RECORD=41|OwnerIndex=1050|IndexInSheet=23|OwnerPartId=-1|Location.X=1287|Location.Y=691|Color=8388608|FontID=1|IsHidden=T|Text=Solder|Name=Shield Termination|IsMirrored=T
|RECORD=41|OwnerIndex=1050|IndexInSheet=24|OwnerPartId=-1|Location.X=1287|Location.Y=691|Color=8388608|FontID=1|IsHidden=T|Text=901-143-6-RFX9011436RFXARFX1232|Name=Other Names|IsMirrored=T
|RECORD=41|OwnerIndex=1050|IndexInSheet=25|OwnerPartId=-1|Location.X=1287|Location.Y=691|Color=8388608|FontID=5|IsHidden=T|Text=http://www.amphenolrf.com/downloads/dl/file/id/2712/product/3102/901_143_6rfx_customer_drawing.pdf|Name=Datasheet URL|IsMirrored=T
|RECORD=41|OwnerIndex=1050|IndexInSheet=26|OwnerPartId=-1|Location.X=1287|Location.Y=691|Color=8388608|FontID=1|IsHidden=T|Text=CoaxialConnectors(RF)|Name=Family|IsMirrored=T
|RECORD=41|OwnerIndex=1050|IndexInSheet=27|OwnerPartId=-1|Location.X=1287|Location.Y=691|Color=8388608|FontID=1|IsHidden=T|Text=SMA,RFX|Name=Online Catalog|IsMirrored=T
|RECORD=41|OwnerIndex=1050|IndexInSheet=28|OwnerPartId=-1|Location.X=1287|Location.Y=691|Color=8388608|FontID=1|IsHidden=T|Text=18GHz|Name=Frequency - Max|IsMirrored=T
|RECORD=41|OwnerIndex=1050|IndexInSheet=29|OwnerPartId=-1|Location.X=1287|Location.Y=691|Color=8388608|FontID=1|IsHidden=T|Text=Solder|Name=Contact Termination|IsMirrored=T
|RECORD=41|OwnerIndex=1050|IndexInSheet=30|OwnerPartId=-1|Location.X=1287|Location.Y=691|Color=8388608|FontID=5|IsHidden=T|Text=http://www.amphenol.com/|Name=Manufacturer URL|IsMirrored=T
|RECORD=41|OwnerIndex=1050|IndexInSheet=31|OwnerPartId=-1|Location.X=1287|Location.Y=691|Color=8388608|FontID=1|IsHidden=T|Text=Amphenol|Name=Manufacturer|IsMirrored=T
|RECORD=41|OwnerIndex=1050|IndexInSheet=32|OwnerPartId=-1|Location.X=1287|Location.Y=691|Color=8388608|FontID=1|IsHidden=T|Text=-65°C~165°C|Name=Operating Temperature|IsMirrored=T
|RECORD=41|OwnerIndex=1050|IndexInSheet=33|OwnerPartId=-1|Location.X=1287|Location.Y=691|Color=8388608|FontID=1|IsHidden=T|Text=Connectors,Interconnects|Name=Category|IsMirrored=T
|RECORD=41|OwnerIndex=1050|IndexInSheet=34|OwnerPartId=-1|Location.X=1287|Location.Y=691|Color=8388608|FontID=1|IsHidden=T|Text=Bulk|Name=Packaging|IsMirrored=T
|RECORD=41|OwnerIndex=1050|IndexInSheet=35|OwnerPartId=-1|Location.X=1287|Location.Y=691|Color=8388608|FontID=1|IsHidden=T|Text=Gold|Name=Body Finish|IsMirrored=T
|RECORD=41|OwnerIndex=1050|IndexInSheet=36|OwnerPartId=-1|Location.X=1287|Location.Y=691|Color=8388608|FontID=1|IsHidden=T|Text=Polytetrafluoroethylene(PTFE)|Name=Dielectric Material|IsMirrored=T
|RECORD=41|OwnerIndex=1050|IndexInSheet=37|OwnerPartId=-1|Location.X=1287|Location.Y=691|Color=8388608|FontID=1|IsHidden=T|Text=BerylliumCopper|Name=Center Contact Material|IsMirrored=T
|RECORD=41|OwnerIndex=1050|IndexInSheet=38|OwnerPartId=-1|Location.X=1287|Location.Y=691|Color=8388608|FontID=1|IsHidden=T|Text=50Ohm|Name=Impedance|IsMirrored=T
|RECORD=41|OwnerIndex=1050|IndexInSheet=39|OwnerPartId=-1|Location.X=1287|Location.Y=691|Color=8388608|FontID=1|IsHidden=T|Text=-|Name=Features|IsMirrored=T
|RECORD=41|OwnerIndex=1050|IndexInSheet=40|OwnerPartId=-1|Location.X=1287|Location.Y=691|Color=8388608|FontID=1|IsHidden=T|Text=SMA|Name=Connector Style|IsMirrored=T
|RECORD=41|OwnerIndex=1050|IndexInSheet=41|OwnerPartId=-1|Location.X=1287|Location.Y=691|Color=8388608|FontID=1|IsHidden=T|Text=Gold|Name=Center Contact Plating|IsMirrored=T
|RECORD=41|OwnerIndex=1050|IndexInSheet=42|OwnerPartId=-1|Location.X=1287|Location.Y=691|Color=8388608|FontID=1|IsHidden=T|Text=Rev. C, 06/2010|Name=Datasheet Version|IsMirrored=T
|RECORD=41|OwnerIndex=1050|IndexInSheet=43|OwnerPartId=-1|Location.X=1287|Location.Y=691|Color=8388608|FontID=1|IsHidden=T|Text=-|Name=Ingress Protection|IsMirrored=T
|RECORD=34|OwnerIndex=1050|IndexInSheet=-1|OwnerPartId=-1|Location.X=1290|Location.Y=700|Color=8388608|FontID=1|Text=J7|Name=Designator|ReadOnlyState=1|IsMirrored=T
|RECORD=41|OwnerIndex=1050|IndexInSheet=-1|OwnerPartId=-1|Location.X=1290|Location.Y=690|Color=8388608|FontID=1|Text=901-143-6RFX|Name=Comment|IsMirrored=T
|RECORD=44|OwnerIndex=1050
|RECORD=45|OwnerIndex=1102|IndexInSheet=-1|Description=THD, 5-Leads, Body 7x7mm, Pitch 2.54mm|UseComponentLibrary=T|ModelName=AMPH-901-143-6RFX_V|ModelType=PCBLIB|IsCurrent=T|DatalinksLocked=T|DatabaseDatalinksLocked=T
|RECORD=46|OwnerIndex=1103
|RECORD=48|OwnerIndex=1103
|RECORD=41|OwnerIndex=1105|IndexInSheet=-1|OwnerPartId=-1|Color=8388608|FontID=1|Text=2D|Name=Available Preview Images
|RECORD=1|LibReference=CN-1P-M-RF3|ComponentDescription=Ultra Miniature Coaxial Connector Jack, 60 V, 50 Ohm, -40 to 90 degC, RoHS, Tape and Reel|PartCount=2|DisplayModeCount=1|IndexInSheet=120|OwnerPartId=-1|Location.X=1330|Location.Y=510|IsMirrored=T|CurrentPartId=1|LibraryPath=*|SourceLibraryName=Altium Content Vault|TargetFileName=*|AreaColor=11599871|Color=128|PartIDLocked=T|DesignItemId=CMP-2000-07505-1|AllPinCount=3
|RECORD=8|OwnerIndex=1107|IsNotAccesible=T|OwnerPartId=1|Location.X=1310|Location.Y=490|Radius=20|SecondaryRadius=20|LineWidth=1|Color=16711680|AreaColor=16777215
|RECORD=8|OwnerIndex=1107|IsNotAccesible=T|IndexInSheet=1|OwnerPartId=1|Location.X=1310|Location.Y=490|Radius=4|SecondaryRadius=4|LineWidth=1|Color=16711680|AreaColor=16777215
|RECORD=2|OwnerIndex=1107|OwnerPartId=1|FormalType=1|Electrical=4|PinConglomerate=51|PinLength=10|Location.X=1320|Location.Y=470|Name=1|Designator=1|PinPropagationDelay=0.000000E+000
|RECORD=2|OwnerIndex=1107|OwnerPartId=1|FormalType=1|Electrical=4|PinConglomerate=48|PinLength=10|Location.X=1330|Location.Y=490|Name=2|Designator=2|PinPropagationDelay=0.000000E+000
|RECORD=2|OwnerIndex=1107|OwnerPartId=1|FormalType=1|Electrical=4|PinConglomerate=51|PinLength=10|Location.X=1300|Location.Y=470|Name=3|Designator=3|PinPropagationDelay=0.000000E+000
|RECORD=6|OwnerIndex=1107|IsNotAccesible=T|IndexInSheet=5|OwnerPartId=1|LineWidth=1|Color=16711680|LocationCount=5|X1=1330|Y1=470|X2=1330|Y2=510|X3=1290|Y3=510|X4=1290|Y4=470|X5=1330|Y5=470
|RECORD=6|OwnerIndex=1107|IsNotAccesible=T|IndexInSheet=6|OwnerPartId=1|LineWidth=1|Color=16711680|LocationCount=2|X1=1330|Y1=490|X2=1314|Y2=490
|RECORD=41|OwnerIndex=1107|IndexInSheet=7|OwnerPartId=-1|Location.X=1289|Location.Y=511|Color=8388608|FontID=1|IsHidden=T|Text=Straight|Name=Orientation|IsMirrored=T
|RECORD=41|OwnerIndex=1107|IndexInSheet=8|OwnerPartId=-1|Location.X=1289|Location.Y=511|Color=8388608|FontID=1|IsHidden=T|Text=Female|Name=Gender|IsMirrored=T
|RECORD=41|OwnerIndex=1107|IndexInSheet=9|OwnerPartId=-1|Location.X=1289|Location.Y=511|Color=8388608|FontID=1|IsHidden=T|Text=Vertical|Name=PCB Mounting Orientation|IsMirrored=T
|RECORD=41|OwnerIndex=1107|IndexInSheet=10|OwnerPartId=-1|Location.X=1289|Location.Y=511|Color=8388608|FontID=1|IsHidden=T|Text=SurfaceMount|Name=Mount|IsMirrored=T
|RECORD=41|OwnerIndex=1107|IndexInSheet=11|OwnerPartId=-1|Location.X=1289|Location.Y=511|Color=8388608|FontID=1|IsHidden=T|Text=3mm|Name=Length|IsMirrored=T
|RECORD=41|OwnerIndex=1107|IndexInSheet=12|OwnerPartId=-1|Location.X=1289|Location.Y=511|Color=8388608|FontID=1|IsHidden=T|Text=TapeandReel|Name=Packaging|IsMirrored=T
|RECORD=41|OwnerIndex=1107|IndexInSheet=13|OwnerPartId=-1|Location.X=1289|Location.Y=511|Color=8388608|FontID=1|IsHidden=T|Text=Jack|Name=Connector Type|IsMirrored=T
|RECORD=41|OwnerIndex=1107|IndexInSheet=14|OwnerPartId=-1|Location.X=1289|Location.Y=511|Color=8388608|FontID=1|IsHidden=T|Text=LeadFree|Name=Lead Free|IsMirrored=T
|RECORD=41|OwnerIndex=1107|IndexInSheet=15|OwnerPartId=-1|Location.X=1289|Location.Y=511|Color=8388608|FontID=1|IsHidden=T|Text=1|Name=Package Quantity|IsMirrored=T
|RECORD=41|OwnerIndex=1107|IndexInSheet=16|OwnerPartId=-1|Location.X=1289|Location.Y=511|Color=8388608|FontID=1|IsHidden=T|Text=SMD/SMT|Name=Termination|IsMirrored=T
|RECORD=41|OwnerIndex=1107|IndexInSheet=17|OwnerPartId=-1|Location.X=1289|Location.Y=511|Color=8388608|FontID=1|IsHidden=T|Text=CopperAlloy|Name=Contact Material|IsMirrored=T
|RECORD=41|OwnerIndex=1107|IndexInSheet=18|OwnerPartId=-1|Location.X=1289|Location.Y=511|Color=8388608|FontID=1|IsHidden=T|Text=Pull|Name=Fastening Type|IsMirrored=T
|RECORD=41|OwnerIndex=1107|IndexInSheet=19|OwnerPartId=-1|Location.X=1289|Location.Y=511|Color=8388608|FontID=1|IsHidden=T|Text=true|Name=RoHSCompliant|IsMirrored=T
|RECORD=41|OwnerIndex=1107|IndexInSheet=20|OwnerPartId=-1|Location.X=1289|Location.Y=511|Color=8388608|FontID=1|IsHidden=T|Text=LiquidCrystalPolymer|Name=Body Material|IsMirrored=T
|RECORD=41|OwnerIndex=1107|IndexInSheet=21|OwnerPartId=-1|Location.X=1289|Location.Y=511|Color=8388608|FontID=1|IsHidden=T|Text=SMD/SMT|Name=Case\/Package|IsMirrored=T
|RECORD=41|OwnerIndex=1107|IndexInSheet=22|OwnerPartId=-1|Location.X=1289|Location.Y=511|Color=8388608|FontID=1|IsHidden=T|Text=90degC|Name=Max Operating Temperature|IsMirrored=T
|RECORD=41|OwnerIndex=1107|IndexInSheet=23|OwnerPartId=-1|Location.X=1289|Location.Y=511|Color=8388608|FontID=1|IsHidden=T|Text=50Ohm|Name=Impedance|IsMirrored=T
|RECORD=41|OwnerIndex=1107|IndexInSheet=24|OwnerPartId=-1|Location.X=1289|Location.Y=511|Color=8388608|FontID=5|IsHidden=T|Text=http://www.te.com/commerce/DocumentDelivery/DDEController?Action=srchrtrv&DocNm=1909763&DocType=Customer+Drawing&DocLang=English|Name=Datasheet URL|IsMirrored=T
|RECORD=41|OwnerIndex=1107|IndexInSheet=25|OwnerPartId=-1|Location.X=1289|Location.Y=511|Color=8388608|FontID=1|IsHidden=T|Text=Gold|Name=Contact Plating|IsMirrored=T
|RECORD=41|OwnerIndex=1107|IndexInSheet=26|OwnerPartId=-1|Location.X=1289|Location.Y=511|Color=8388608|FontID=1|IsHidden=T|Text=SurfaceMount|Name=Mounting Technology|IsMirrored=T
|RECORD=41|OwnerIndex=1107|IndexInSheet=27|OwnerPartId=-1|Location.X=1289|Location.Y=511|Color=8388608|FontID=1|IsHidden=T|Text=6GHz|Name=Max Frequency|IsMirrored=T
|RECORD=41|OwnerIndex=1107|IndexInSheet=28|OwnerPartId=-1|Location.X=1289|Location.Y=511|Color=8388608|FontID=1|IsHidden=T|Text=TECO-1909763-1|Name=Package Reference|IsMirrored=T
|RECORD=41|OwnerIndex=1107|IndexInSheet=29|OwnerPartId=-1|Location.X=1289|Location.Y=511|Color=8388608|FontID=1|IsHidden=T|Text=Thermoplastic|Name=Insulation Material|IsMirrored=T
|RECORD=41|OwnerIndex=1107|IndexInSheet=30|OwnerPartId=-1|Location.X=1289|Location.Y=511|Color=8388608|FontID=1|IsHidden=T|Text=-40degC|Name=Min Operating Temperature|IsMirrored=T
|RECORD=41|OwnerIndex=1107|IndexInSheet=31|OwnerPartId=-1|Location.X=1289|Location.Y=511|Color=8388608|FontID=5|IsHidden=T|Text=http://www.te.com/|Name=Manufacturer URL|IsMirrored=T
|RECORD=41|OwnerIndex=1107|IndexInSheet=32|OwnerPartId=-1|Location.X=1289|Location.Y=511|Color=8388608|FontID=1|IsHidden=T|Text=Gold|Name=Body Plating|IsMirrored=T
|RECORD=41|OwnerIndex=1107|IndexInSheet=33|OwnerPartId=-1|Location.X=1289|Location.Y=511|Color=8388608|FontID=1|IsHidden=T|Text=Polymer|Name=Dielectric Material|IsMirrored=T
|RECORD=41|OwnerIndex=1107|IndexInSheet=34|OwnerPartId=-1|Location.X=1289|Location.Y=511|Color=8388608|FontID=1|IsHidden=T|Text=TE Connectivity|Name=Manufacturer|IsMirrored=T
|RECORD=41|OwnerIndex=1107|IndexInSheet=35|OwnerPartId=-1|Location.X=1289|Location.Y=511|Color=8388608|FontID=1|IsHidden=T|Text=Compliant|Name=ELV|IsMirrored=T
|RECORD=41|OwnerIndex=1107|IndexInSheet=36|OwnerPartId=-1|Location.X=1289|Location.Y=511|Color=8388608|FontID=1|IsHidden=T|Text=Rev. B2, 11/2015|Name=Datasheet Version|IsMirrored=T
|RECORD=41|OwnerIndex=1107|IndexInSheet=37|OwnerPartId=-1|Location.X=1289|Location.Y=511|Color=8388608|FontID=1|IsHidden=T|Text=No|Name=Radiation Hardening|IsMirrored=T
|RECORD=41|OwnerIndex=1107|IndexInSheet=38|OwnerPartId=-1|Location.X=1289|Location.Y=511|Color=8388608|FontID=1|IsHidden=T|Text=3-Pin Surface Mount Device, Body 2.6 x 2.6 mm|Name=Package Description|IsMirrored=T
|RECORD=41|OwnerIndex=1107|IndexInSheet=39|OwnerPartId=-1|Location.X=1289|Location.Y=511|Color=8388608|FontID=1|IsHidden=T|Text=Beige|Name=Housing Colour|IsMirrored=T
|RECORD=34|OwnerIndex=1107|IndexInSheet=-1|OwnerPartId=-1|Location.X=1290|Location.Y=520|Color=8388608|FontID=1|Text=J10|Name=Designator|ReadOnlyState=1|IsMirrored=T
|RECORD=41|OwnerIndex=1107|IndexInSheet=-1|OwnerPartId=-1|Location.X=1290|Location.Y=510|Color=8388608|FontID=1|Text=1909763-1|Name=Comment|IsMirrored=T
|RECORD=44|OwnerIndex=1107
|RECORD=45|OwnerIndex=1153|IndexInSheet=-1|Description=SMD, 3-Leads, Body 2.6x2.6mm, Height 1.25mm|UseComponentLibrary=T|ModelName=TECO-1909763-1_V|ModelType=PCBLIB|IsCurrent=T|DatalinksLocked=T|DatabaseDatalinksLocked=T
|RECORD=46|OwnerIndex=1154
|RECORD=48|OwnerIndex=1154
|RECORD=41|OwnerIndex=1156|IndexInSheet=-1|OwnerPartId=-1|Color=8388608|FontID=1|Text=2D|Name=Available Preview Images
|RECORD=1|LibReference=CN-S-4F-RF5|ComponentDescription=Coaxial connector, 50 Ohm, -65 to 165 degC, 5-Pin THD, RoHS, Bulk|PartCount=2|DisplayModeCount=1|IndexInSheet=121|OwnerPartId=-1|Location.X=1330|Location.Y=420|IsMirrored=T|CurrentPartId=1|LibraryPath=*|SourceLibraryName=Altium Content Vault|TargetFileName=*|AreaColor=11599871|Color=128|PartIDLocked=T|DesignItemId=CMP-2000-05705-1|AllPinCount=5
|RECORD=2|OwnerIndex=1158|OwnerPartId=1|FormalType=1|Electrical=4|PinConglomerate=51|PinLength=10|Location.X=1290|Location.Y=380|Name=5|Designator=5|SwapIDPart=Ž&Ž1|PinPropagationDelay=0.000000E+000
|RECORD=8|OwnerIndex=1158|IsNotAccesible=T|IndexInSheet=1|OwnerPartId=1|Location.X=1310|Location.Y=400|Radius=20|SecondaryRadius=20|LineWidth=1|Color=16711680|AreaColor=16777215
|RECORD=8|OwnerIndex=1158|IsNotAccesible=T|IndexInSheet=2|OwnerPartId=1|Location.X=1310|Location.Y=400|Radius=4|SecondaryRadius=4|LineWidth=1|Color=16711680|AreaColor=16777215
|RECORD=2|OwnerIndex=1158|OwnerPartId=1|FormalType=1|Electrical=4|PinConglomerate=48|PinLength=10|Location.X=1330|Location.Y=400|Name=1|Designator=1|PinPropagationDelay=0.000000E+000
|RECORD=2|OwnerIndex=1158|OwnerPartId=1|FormalType=1|Electrical=4|PinConglomerate=51|PinLength=10|Location.X=1320|Location.Y=380|Name=2|Designator=2|PinPropagationDelay=0.000000E+000
|RECORD=2|OwnerIndex=1158|OwnerPartId=1|FormalType=1|Electrical=4|PinConglomerate=51|PinLength=10|Location.X=1310|Location.Y=380|Name=3|Designator=3|PinPropagationDelay=0.000000E+000
|RECORD=2|OwnerIndex=1158|OwnerPartId=1|FormalType=1|Electrical=4|PinConglomerate=51|PinLength=10|Location.X=1300|Location.Y=380|Name=4|Designator=4|PinPropagationDelay=0.000000E+000
|RECORD=6|OwnerIndex=1158|IsNotAccesible=T|IndexInSheet=7|OwnerPartId=1|LineWidth=1|Color=16711680|LocationCount=5|X1=1330|Y1=380|X2=1330|Y2=420|X3=1290|Y3=420|X4=1290|Y4=380|X5=1330|Y5=380
|RECORD=6|OwnerIndex=1158|IsNotAccesible=T|IndexInSheet=8|OwnerPartId=1|LineWidth=1|Color=16711680|LocationCount=2|X1=1330|Y1=400|X2=1314|Y2=400
|RECORD=41|OwnerIndex=1158|IndexInSheet=9|OwnerPartId=-1|Location.X=1287|Location.Y=421|Color=8388608|FontID=1|IsHidden=T|Text=ThroughHole|Name=Mounting Technology|IsMirrored=T
|RECORD=41|OwnerIndex=1158|IndexInSheet=10|OwnerPartId=-1|Location.X=1287|Location.Y=421|Color=8388608|FontID=1|IsHidden=T|Text=ThroughHole,RightAngle|Name=Mounting Type|IsMirrored=T
|RECORD=41|OwnerIndex=1158|IndexInSheet=11|OwnerPartId=-1|Location.X=1287|Location.Y=421|Color=8388608|FontID=1|IsHidden=T|Text=-|Name=Cable Group|IsMirrored=T
|RECORD=41|OwnerIndex=1158|IndexInSheet=12|OwnerPartId=-1|Location.X=1287|Location.Y=421|Color=8388608|FontID=1|IsHidden=T|Text=901-143-6RFXMountingHole|Name=Catalog Drawings|IsMirrored=T
|RECORD=41|OwnerIndex=1158|IndexInSheet=13|OwnerPartId=-1|Location.X=1287|Location.Y=421|Color=8388608|FontID=1|IsHidden=T|Text=901-143-6RFX.igs|Name=3D Model|IsMirrored=T
|RECORD=41|OwnerIndex=1158|IndexInSheet=14|OwnerPartId=-1|Location.X=1287|Location.Y=421|Color=8388608|FontID=1|IsHidden=T|Text=-|Name=Series|IsMirrored=T
|RECORD=41|OwnerIndex=1158|IndexInSheet=15|OwnerPartId=-1|Location.X=1287|Location.Y=421|Color=8388608|FontID=1|IsHidden=T|Text=5-Pin Through Hole Device, Body 7 x 7 mm, Pitch 2.54 mm|Name=Package Description|IsMirrored=T
|RECORD=41|OwnerIndex=1158|IndexInSheet=16|OwnerPartId=-1|Location.X=1287|Location.Y=421|Color=8388608|FontID=1|IsHidden=T|Text=901-143-6RFX|Name=Package Reference|IsMirrored=T
|RECORD=41|OwnerIndex=1158|IndexInSheet=17|OwnerPartId=-1|Location.X=1287|Location.Y=421|Color=8388608|FontID=1|IsHidden=T|Text=Brass|Name=Body Material|IsMirrored=T
|RECORD=41|OwnerIndex=1158|IndexInSheet=18|OwnerPartId=-1|Location.X=1287|Location.Y=421|Color=8388608|FontID=1|IsHidden=T|Text=-|Name=Voltage Rating|IsMirrored=T
|RECORD=41|OwnerIndex=1158|IndexInSheet=19|OwnerPartId=-1|Location.X=1287|Location.Y=421|Color=8388608|FontID=1|IsHidden=T|Text=1|Name=Standard Package|IsMirrored=T
|RECORD=41|OwnerIndex=1158|IndexInSheet=20|OwnerPartId=-1|Location.X=1287|Location.Y=421|Color=8388608|FontID=1|IsHidden=T|Text=Jack,FemaleSocket|Name=Connector Type|IsMirrored=T
|RECORD=41|OwnerIndex=1158|IndexInSheet=21|OwnerPartId=-1|Location.X=1287|Location.Y=421|Color=8388608|FontID=1|IsHidden=T|Text=Threaded|Name=Fastening Type|IsMirrored=T
|RECORD=41|OwnerIndex=1158|IndexInSheet=22|OwnerPartId=-1|Location.X=1287|Location.Y=421|Color=8388608|FontID=1|IsHidden=T|Text=Gold|Name=Housing Color|IsMirrored=T
|RECORD=41|OwnerIndex=1158|IndexInSheet=23|OwnerPartId=-1|Location.X=1287|Location.Y=421|Color=8388608|FontID=1|IsHidden=T|Text=Solder|Name=Shield Termination|IsMirrored=T
|RECORD=41|OwnerIndex=1158|IndexInSheet=24|OwnerPartId=-1|Location.X=1287|Location.Y=421|Color=8388608|FontID=1|IsHidden=T|Text=901-143-6-RFX9011436RFXARFX1232|Name=Other Names|IsMirrored=T
|RECORD=41|OwnerIndex=1158|IndexInSheet=25|OwnerPartId=-1|Location.X=1287|Location.Y=421|Color=8388608|FontID=5|IsHidden=T|Text=http://www.amphenolrf.com/downloads/dl/file/id/2712/product/3102/901_143_6rfx_customer_drawing.pdf|Name=Datasheet URL|IsMirrored=T
|RECORD=41|OwnerIndex=1158|IndexInSheet=26|OwnerPartId=-1|Location.X=1287|Location.Y=421|Color=8388608|FontID=1|IsHidden=T|Text=CoaxialConnectors(RF)|Name=Family|IsMirrored=T
|RECORD=41|OwnerIndex=1158|IndexInSheet=27|OwnerPartId=-1|Location.X=1287|Location.Y=421|Color=8388608|FontID=1|IsHidden=T|Text=SMA,RFX|Name=Online Catalog|IsMirrored=T
|RECORD=41|OwnerIndex=1158|IndexInSheet=28|OwnerPartId=-1|Location.X=1287|Location.Y=421|Color=8388608|FontID=1|IsHidden=T|Text=18GHz|Name=Frequency - Max|IsMirrored=T
|RECORD=41|OwnerIndex=1158|IndexInSheet=29|OwnerPartId=-1|Location.X=1287|Location.Y=421|Color=8388608|FontID=1|IsHidden=T|Text=Solder|Name=Contact Termination|IsMirrored=T
|RECORD=41|OwnerIndex=1158|IndexInSheet=30|OwnerPartId=-1|Location.X=1287|Location.Y=421|Color=8388608|FontID=5|IsHidden=T|Text=http://www.amphenol.com/|Name=Manufacturer URL|IsMirrored=T
|RECORD=41|OwnerIndex=1158|IndexInSheet=31|OwnerPartId=-1|Location.X=1287|Location.Y=421|Color=8388608|FontID=1|IsHidden=T|Text=Amphenol|Name=Manufacturer|IsMirrored=T
|RECORD=41|OwnerIndex=1158|IndexInSheet=32|OwnerPartId=-1|Location.X=1287|Location.Y=421|Color=8388608|FontID=1|IsHidden=T|Text=-65°C~165°C|Name=Operating Temperature|IsMirrored=T
|RECORD=41|OwnerIndex=1158|IndexInSheet=33|OwnerPartId=-1|Location.X=1287|Location.Y=421|Color=8388608|FontID=1|IsHidden=T|Text=Connectors,Interconnects|Name=Category|IsMirrored=T
|RECORD=41|OwnerIndex=1158|IndexInSheet=34|OwnerPartId=-1|Location.X=1287|Location.Y=421|Color=8388608|FontID=1|IsHidden=T|Text=Bulk|Name=Packaging|IsMirrored=T
|RECORD=41|OwnerIndex=1158|IndexInSheet=35|OwnerPartId=-1|Location.X=1287|Location.Y=421|Color=8388608|FontID=1|IsHidden=T|Text=Gold|Name=Body Finish|IsMirrored=T
|RECORD=41|OwnerIndex=1158|IndexInSheet=36|OwnerPartId=-1|Location.X=1287|Location.Y=421|Color=8388608|FontID=1|IsHidden=T|Text=Polytetrafluoroethylene(PTFE)|Name=Dielectric Material|IsMirrored=T
|RECORD=41|OwnerIndex=1158|IndexInSheet=37|OwnerPartId=-1|Location.X=1287|Location.Y=421|Color=8388608|FontID=1|IsHidden=T|Text=BerylliumCopper|Name=Center Contact Material|IsMirrored=T
|RECORD=41|OwnerIndex=1158|IndexInSheet=38|OwnerPartId=-1|Location.X=1287|Location.Y=421|Color=8388608|FontID=1|IsHidden=T|Text=50Ohm|Name=Impedance|IsMirrored=T
|RECORD=41|OwnerIndex=1158|IndexInSheet=39|OwnerPartId=-1|Location.X=1287|Location.Y=421|Color=8388608|FontID=1|IsHidden=T|Text=-|Name=Features|IsMirrored=T
|RECORD=41|OwnerIndex=1158|IndexInSheet=40|OwnerPartId=-1|Location.X=1287|Location.Y=421|Color=8388608|FontID=1|IsHidden=T|Text=SMA|Name=Connector Style|IsMirrored=T
|RECORD=41|OwnerIndex=1158|IndexInSheet=41|OwnerPartId=-1|Location.X=1287|Location.Y=421|Color=8388608|FontID=1|IsHidden=T|Text=Gold|Name=Center Contact Plating|IsMirrored=T
|RECORD=41|OwnerIndex=1158|IndexInSheet=42|OwnerPartId=-1|Location.X=1287|Location.Y=421|Color=8388608|FontID=1|IsHidden=T|Text=Rev. C, 06/2010|Name=Datasheet Version|IsMirrored=T
|RECORD=41|OwnerIndex=1158|IndexInSheet=43|OwnerPartId=-1|Location.X=1287|Location.Y=421|Color=8388608|FontID=1|IsHidden=T|Text=-|Name=Ingress Protection|IsMirrored=T
|RECORD=34|OwnerIndex=1158|IndexInSheet=-1|OwnerPartId=-1|Location.X=1290|Location.Y=430|Color=8388608|FontID=1|Text=J12|Name=Designator|ReadOnlyState=1|IsMirrored=T
|RECORD=41|OwnerIndex=1158|IndexInSheet=-1|OwnerPartId=-1|Location.X=1290|Location.Y=420|Color=8388608|FontID=1|Text=901-143-6RFX|Name=Comment|IsMirrored=T
|RECORD=44|OwnerIndex=1158
|RECORD=45|OwnerIndex=1210|IndexInSheet=-1|Description=THD, 5-Leads, Body 7x7mm, Pitch 2.54mm|UseComponentLibrary=T|ModelName=AMPH-901-143-6RFX_V|ModelType=PCBLIB|IsCurrent=T|DatalinksLocked=T|DatabaseDatalinksLocked=T
|RECORD=46|OwnerIndex=1211
|RECORD=48|OwnerIndex=1211
|RECORD=41|OwnerIndex=1213|IndexInSheet=-1|OwnerPartId=-1|Color=8388608|FontID=1|Text=2D|Name=Available Preview Images
|RECORD=1|LibReference=CN-1P-M-RF3|ComponentDescription=Ultra Miniature Coaxial Connector Jack, 60 V, 50 Ohm, -40 to 90 degC, RoHS, Tape and Reel|PartCount=2|DisplayModeCount=1|IndexInSheet=122|OwnerPartId=-1|Location.X=1050|Location.Y=510|IsMirrored=T|CurrentPartId=1|LibraryPath=*|SourceLibraryName=Altium Content Vault|TargetFileName=*|AreaColor=11599871|Color=128|PartIDLocked=T|DesignItemId=CMP-2000-07505-1|AllPinCount=3
|RECORD=8|OwnerIndex=1215|IsNotAccesible=T|OwnerPartId=1|Location.X=1030|Location.Y=490|Radius=20|SecondaryRadius=20|LineWidth=1|Color=16711680|AreaColor=16777215
|RECORD=8|OwnerIndex=1215|IsNotAccesible=T|IndexInSheet=1|OwnerPartId=1|Location.X=1030|Location.Y=490|Radius=4|SecondaryRadius=4|LineWidth=1|Color=16711680|AreaColor=16777215
|RECORD=2|OwnerIndex=1215|OwnerPartId=1|FormalType=1|Electrical=4|PinConglomerate=51|PinLength=10|Location.X=1040|Location.Y=470|Name=1|Designator=1|PinPropagationDelay=0.000000E+000
|RECORD=2|OwnerIndex=1215|OwnerPartId=1|FormalType=1|Electrical=4|PinConglomerate=48|PinLength=10|Location.X=1050|Location.Y=490|Name=2|Designator=2|PinPropagationDelay=0.000000E+000
|RECORD=2|OwnerIndex=1215|OwnerPartId=1|FormalType=1|Electrical=4|PinConglomerate=51|PinLength=10|Location.X=1020|Location.Y=470|Name=3|Designator=3|PinPropagationDelay=0.000000E+000
|RECORD=6|OwnerIndex=1215|IsNotAccesible=T|IndexInSheet=5|OwnerPartId=1|LineWidth=1|Color=16711680|LocationCount=5|X1=1050|Y1=470|X2=1050|Y2=510|X3=1010|Y3=510|X4=1010|Y4=470|X5=1050|Y5=470
|RECORD=6|OwnerIndex=1215|IsNotAccesible=T|IndexInSheet=6|OwnerPartId=1|LineWidth=1|Color=16711680|LocationCount=2|X1=1050|Y1=490|X2=1034|Y2=490
|RECORD=41|OwnerIndex=1215|IndexInSheet=7|OwnerPartId=-1|Location.X=1009|Location.Y=511|Color=8388608|FontID=1|IsHidden=T|Text=Straight|Name=Orientation|IsMirrored=T
|RECORD=41|OwnerIndex=1215|IndexInSheet=8|OwnerPartId=-1|Location.X=1009|Location.Y=511|Color=8388608|FontID=1|IsHidden=T|Text=Female|Name=Gender|IsMirrored=T
|RECORD=41|OwnerIndex=1215|IndexInSheet=9|OwnerPartId=-1|Location.X=1009|Location.Y=511|Color=8388608|FontID=1|IsHidden=T|Text=Vertical|Name=PCB Mounting Orientation|IsMirrored=T
|RECORD=41|OwnerIndex=1215|IndexInSheet=10|OwnerPartId=-1|Location.X=1009|Location.Y=511|Color=8388608|FontID=1|IsHidden=T|Text=SurfaceMount|Name=Mount|IsMirrored=T
|RECORD=41|OwnerIndex=1215|IndexInSheet=11|OwnerPartId=-1|Location.X=1009|Location.Y=511|Color=8388608|FontID=1|IsHidden=T|Text=3mm|Name=Length|IsMirrored=T
|RECORD=41|OwnerIndex=1215|IndexInSheet=12|OwnerPartId=-1|Location.X=1009|Location.Y=511|Color=8388608|FontID=1|IsHidden=T|Text=TapeandReel|Name=Packaging|IsMirrored=T
|RECORD=41|OwnerIndex=1215|IndexInSheet=13|OwnerPartId=-1|Location.X=1009|Location.Y=511|Color=8388608|FontID=1|IsHidden=T|Text=Jack|Name=Connector Type|IsMirrored=T
|RECORD=41|OwnerIndex=1215|IndexInSheet=14|OwnerPartId=-1|Location.X=1009|Location.Y=511|Color=8388608|FontID=1|IsHidden=T|Text=LeadFree|Name=Lead Free|IsMirrored=T
|RECORD=41|OwnerIndex=1215|IndexInSheet=15|OwnerPartId=-1|Location.X=1009|Location.Y=511|Color=8388608|FontID=1|IsHidden=T|Text=1|Name=Package Quantity|IsMirrored=T
|RECORD=41|OwnerIndex=1215|IndexInSheet=16|OwnerPartId=-1|Location.X=1009|Location.Y=511|Color=8388608|FontID=1|IsHidden=T|Text=SMD/SMT|Name=Termination|IsMirrored=T
|RECORD=41|OwnerIndex=1215|IndexInSheet=17|OwnerPartId=-1|Location.X=1009|Location.Y=511|Color=8388608|FontID=1|IsHidden=T|Text=CopperAlloy|Name=Contact Material|IsMirrored=T
|RECORD=41|OwnerIndex=1215|IndexInSheet=18|OwnerPartId=-1|Location.X=1009|Location.Y=511|Color=8388608|FontID=1|IsHidden=T|Text=Pull|Name=Fastening Type|IsMirrored=T
|RECORD=41|OwnerIndex=1215|IndexInSheet=19|OwnerPartId=-1|Location.X=1009|Location.Y=511|Color=8388608|FontID=1|IsHidden=T|Text=true|Name=RoHSCompliant|IsMirrored=T
|RECORD=41|OwnerIndex=1215|IndexInSheet=20|OwnerPartId=-1|Location.X=1009|Location.Y=511|Color=8388608|FontID=1|IsHidden=T|Text=LiquidCrystalPolymer|Name=Body Material|IsMirrored=T
|RECORD=41|OwnerIndex=1215|IndexInSheet=21|OwnerPartId=-1|Location.X=1009|Location.Y=511|Color=8388608|FontID=1|IsHidden=T|Text=SMD/SMT|Name=Case\/Package|IsMirrored=T
|RECORD=41|OwnerIndex=1215|IndexInSheet=22|OwnerPartId=-1|Location.X=1009|Location.Y=511|Color=8388608|FontID=1|IsHidden=T|Text=90degC|Name=Max Operating Temperature|IsMirrored=T
|RECORD=41|OwnerIndex=1215|IndexInSheet=23|OwnerPartId=-1|Location.X=1009|Location.Y=511|Color=8388608|FontID=1|IsHidden=T|Text=50Ohm|Name=Impedance|IsMirrored=T
|RECORD=41|OwnerIndex=1215|IndexInSheet=24|OwnerPartId=-1|Location.X=1009|Location.Y=511|Color=8388608|FontID=5|IsHidden=T|Text=http://www.te.com/commerce/DocumentDelivery/DDEController?Action=srchrtrv&DocNm=1909763&DocType=Customer+Drawing&DocLang=English|Name=Datasheet URL|IsMirrored=T
|RECORD=41|OwnerIndex=1215|IndexInSheet=25|OwnerPartId=-1|Location.X=1009|Location.Y=511|Color=8388608|FontID=1|IsHidden=T|Text=Gold|Name=Contact Plating|IsMirrored=T
|RECORD=41|OwnerIndex=1215|IndexInSheet=26|OwnerPartId=-1|Location.X=1009|Location.Y=511|Color=8388608|FontID=1|IsHidden=T|Text=SurfaceMount|Name=Mounting Technology|IsMirrored=T
|RECORD=41|OwnerIndex=1215|IndexInSheet=27|OwnerPartId=-1|Location.X=1009|Location.Y=511|Color=8388608|FontID=1|IsHidden=T|Text=6GHz|Name=Max Frequency|IsMirrored=T
|RECORD=41|OwnerIndex=1215|IndexInSheet=28|OwnerPartId=-1|Location.X=1009|Location.Y=511|Color=8388608|FontID=1|IsHidden=T|Text=TECO-1909763-1|Name=Package Reference|IsMirrored=T
|RECORD=41|OwnerIndex=1215|IndexInSheet=29|OwnerPartId=-1|Location.X=1009|Location.Y=511|Color=8388608|FontID=1|IsHidden=T|Text=Thermoplastic|Name=Insulation Material|IsMirrored=T
|RECORD=41|OwnerIndex=1215|IndexInSheet=30|OwnerPartId=-1|Location.X=1009|Location.Y=511|Color=8388608|FontID=1|IsHidden=T|Text=-40degC|Name=Min Operating Temperature|IsMirrored=T
|RECORD=41|OwnerIndex=1215|IndexInSheet=31|OwnerPartId=-1|Location.X=1009|Location.Y=511|Color=8388608|FontID=5|IsHidden=T|Text=http://www.te.com/|Name=Manufacturer URL|IsMirrored=T
|RECORD=41|OwnerIndex=1215|IndexInSheet=32|OwnerPartId=-1|Location.X=1009|Location.Y=511|Color=8388608|FontID=1|IsHidden=T|Text=Gold|Name=Body Plating|IsMirrored=T
|RECORD=41|OwnerIndex=1215|IndexInSheet=33|OwnerPartId=-1|Location.X=1009|Location.Y=511|Color=8388608|FontID=1|IsHidden=T|Text=Polymer|Name=Dielectric Material|IsMirrored=T
|RECORD=41|OwnerIndex=1215|IndexInSheet=34|OwnerPartId=-1|Location.X=1009|Location.Y=511|Color=8388608|FontID=1|IsHidden=T|Text=TE Connectivity|Name=Manufacturer|IsMirrored=T
|RECORD=41|OwnerIndex=1215|IndexInSheet=35|OwnerPartId=-1|Location.X=1009|Location.Y=511|Color=8388608|FontID=1|IsHidden=T|Text=Compliant|Name=ELV|IsMirrored=T
|RECORD=41|OwnerIndex=1215|IndexInSheet=36|OwnerPartId=-1|Location.X=1009|Location.Y=511|Color=8388608|FontID=1|IsHidden=T|Text=Rev. B2, 11/2015|Name=Datasheet Version|IsMirrored=T
|RECORD=41|OwnerIndex=1215|IndexInSheet=37|OwnerPartId=-1|Location.X=1009|Location.Y=511|Color=8388608|FontID=1|IsHidden=T|Text=No|Name=Radiation Hardening|IsMirrored=T
|RECORD=41|OwnerIndex=1215|IndexInSheet=38|OwnerPartId=-1|Location.X=1009|Location.Y=511|Color=8388608|FontID=1|IsHidden=T|Text=3-Pin Surface Mount Device, Body 2.6 x 2.6 mm|Name=Package Description|IsMirrored=T
|RECORD=41|OwnerIndex=1215|IndexInSheet=39|OwnerPartId=-1|Location.X=1009|Location.Y=511|Color=8388608|FontID=1|IsHidden=T|Text=Beige|Name=Housing Colour|IsMirrored=T
|RECORD=34|OwnerIndex=1215|IndexInSheet=-1|OwnerPartId=-1|Location.X=1010|Location.Y=520|Color=8388608|FontID=1|Text=J9|Name=Designator|ReadOnlyState=1|IsMirrored=T
|RECORD=41|OwnerIndex=1215|IndexInSheet=-1|OwnerPartId=-1|Location.X=1010|Location.Y=510|Color=8388608|FontID=1|Text=1909763-1|Name=Comment|IsMirrored=T
|RECORD=44|OwnerIndex=1215
|RECORD=45|OwnerIndex=1261|IndexInSheet=-1|Description=SMD, 3-Leads, Body 2.6x2.6mm, Height 1.25mm|UseComponentLibrary=T|ModelName=TECO-1909763-1_V|ModelType=PCBLIB|IsCurrent=T|DatalinksLocked=T|DatabaseDatalinksLocked=T
|RECORD=46|OwnerIndex=1262
|RECORD=48|OwnerIndex=1262
|RECORD=41|OwnerIndex=1264|IndexInSheet=-1|OwnerPartId=-1|Color=8388608|FontID=1|Text=2D|Name=Available Preview Images
|RECORD=1|LibReference=CN-S-4F-RF5|ComponentDescription=Coaxial connector, 50 Ohm, -65 to 165 degC, 5-Pin THD, RoHS, Bulk|PartCount=2|DisplayModeCount=1|IndexInSheet=123|OwnerPartId=-1|Location.X=1050|Location.Y=420|IsMirrored=T|CurrentPartId=1|LibraryPath=*|SourceLibraryName=Altium Content Vault|TargetFileName=*|AreaColor=11599871|Color=128|PartIDLocked=T|DesignItemId=CMP-2000-05705-1|AllPinCount=5
|RECORD=2|OwnerIndex=1266|OwnerPartId=1|FormalType=1|Electrical=4|PinConglomerate=51|PinLength=10|Location.X=1010|Location.Y=380|Name=5|Designator=5|SwapIDPart=Ž&Ž1|PinPropagationDelay=0.000000E+000
|RECORD=8|OwnerIndex=1266|IsNotAccesible=T|IndexInSheet=1|OwnerPartId=1|Location.X=1030|Location.Y=400|Radius=20|SecondaryRadius=20|LineWidth=1|Color=16711680|AreaColor=16777215
|RECORD=8|OwnerIndex=1266|IsNotAccesible=T|IndexInSheet=2|OwnerPartId=1|Location.X=1030|Location.Y=400|Radius=4|SecondaryRadius=4|LineWidth=1|Color=16711680|AreaColor=16777215
|RECORD=2|OwnerIndex=1266|OwnerPartId=1|FormalType=1|Electrical=4|PinConglomerate=48|PinLength=10|Location.X=1050|Location.Y=400|Name=1|Designator=1|PinPropagationDelay=0.000000E+000
|RECORD=2|OwnerIndex=1266|OwnerPartId=1|FormalType=1|Electrical=4|PinConglomerate=51|PinLength=10|Location.X=1040|Location.Y=380|Name=2|Designator=2|PinPropagationDelay=0.000000E+000
|RECORD=2|OwnerIndex=1266|OwnerPartId=1|FormalType=1|Electrical=4|PinConglomerate=51|PinLength=10|Location.X=1030|Location.Y=380|Name=3|Designator=3|PinPropagationDelay=0.000000E+000
|RECORD=2|OwnerIndex=1266|OwnerPartId=1|FormalType=1|Electrical=4|PinConglomerate=51|PinLength=10|Location.X=1020|Location.Y=380|Name=4|Designator=4|PinPropagationDelay=0.000000E+000
|RECORD=6|OwnerIndex=1266|IsNotAccesible=T|IndexInSheet=7|OwnerPartId=1|LineWidth=1|Color=16711680|LocationCount=5|X1=1050|Y1=380|X2=1050|Y2=420|X3=1010|Y3=420|X4=1010|Y4=380|X5=1050|Y5=380
|RECORD=6|OwnerIndex=1266|IsNotAccesible=T|IndexInSheet=8|OwnerPartId=1|LineWidth=1|Color=16711680|LocationCount=2|X1=1050|Y1=400|X2=1034|Y2=400
|RECORD=41|OwnerIndex=1266|IndexInSheet=9|OwnerPartId=-1|Location.X=1007|Location.Y=421|Color=8388608|FontID=1|IsHidden=T|Text=ThroughHole|Name=Mounting Technology|IsMirrored=T
|RECORD=41|OwnerIndex=1266|IndexInSheet=10|OwnerPartId=-1|Location.X=1007|Location.Y=421|Color=8388608|FontID=1|IsHidden=T|Text=ThroughHole,RightAngle|Name=Mounting Type|IsMirrored=T
|RECORD=41|OwnerIndex=1266|IndexInSheet=11|OwnerPartId=-1|Location.X=1007|Location.Y=421|Color=8388608|FontID=1|IsHidden=T|Text=-|Name=Cable Group|IsMirrored=T
|RECORD=41|OwnerIndex=1266|IndexInSheet=12|OwnerPartId=-1|Location.X=1007|Location.Y=421|Color=8388608|FontID=1|IsHidden=T|Text=901-143-6RFXMountingHole|Name=Catalog Drawings|IsMirrored=T
|RECORD=41|OwnerIndex=1266|IndexInSheet=13|OwnerPartId=-1|Location.X=1007|Location.Y=421|Color=8388608|FontID=1|IsHidden=T|Text=901-143-6RFX.igs|Name=3D Model|IsMirrored=T
|RECORD=41|OwnerIndex=1266|IndexInSheet=14|OwnerPartId=-1|Location.X=1007|Location.Y=421|Color=8388608|FontID=1|IsHidden=T|Text=-|Name=Series|IsMirrored=T
|RECORD=41|OwnerIndex=1266|IndexInSheet=15|OwnerPartId=-1|Location.X=1007|Location.Y=421|Color=8388608|FontID=1|IsHidden=T|Text=5-Pin Through Hole Device, Body 7 x 7 mm, Pitch 2.54 mm|Name=Package Description|IsMirrored=T
|RECORD=41|OwnerIndex=1266|IndexInSheet=16|OwnerPartId=-1|Location.X=1007|Location.Y=421|Color=8388608|FontID=1|IsHidden=T|Text=901-143-6RFX|Name=Package Reference|IsMirrored=T
|RECORD=41|OwnerIndex=1266|IndexInSheet=17|OwnerPartId=-1|Location.X=1007|Location.Y=421|Color=8388608|FontID=1|IsHidden=T|Text=Brass|Name=Body Material|IsMirrored=T
|RECORD=41|OwnerIndex=1266|IndexInSheet=18|OwnerPartId=-1|Location.X=1007|Location.Y=421|Color=8388608|FontID=1|IsHidden=T|Text=-|Name=Voltage Rating|IsMirrored=T
|RECORD=41|OwnerIndex=1266|IndexInSheet=19|OwnerPartId=-1|Location.X=1007|Location.Y=421|Color=8388608|FontID=1|IsHidden=T|Text=1|Name=Standard Package|IsMirrored=T
|RECORD=41|OwnerIndex=1266|IndexInSheet=20|OwnerPartId=-1|Location.X=1007|Location.Y=421|Color=8388608|FontID=1|IsHidden=T|Text=Jack,FemaleSocket|Name=Connector Type|IsMirrored=T
|RECORD=41|OwnerIndex=1266|IndexInSheet=21|OwnerPartId=-1|Location.X=1007|Location.Y=421|Color=8388608|FontID=1|IsHidden=T|Text=Threaded|Name=Fastening Type|IsMirrored=T
|RECORD=41|OwnerIndex=1266|IndexInSheet=22|OwnerPartId=-1|Location.X=1007|Location.Y=421|Color=8388608|FontID=1|IsHidden=T|Text=Gold|Name=Housing Color|IsMirrored=T
|RECORD=41|OwnerIndex=1266|IndexInSheet=23|OwnerPartId=-1|Location.X=1007|Location.Y=421|Color=8388608|FontID=1|IsHidden=T|Text=Solder|Name=Shield Termination|IsMirrored=T
|RECORD=41|OwnerIndex=1266|IndexInSheet=24|OwnerPartId=-1|Location.X=1007|Location.Y=421|Color=8388608|FontID=1|IsHidden=T|Text=901-143-6-RFX9011436RFXARFX1232|Name=Other Names|IsMirrored=T
|RECORD=41|OwnerIndex=1266|IndexInSheet=25|OwnerPartId=-1|Location.X=1007|Location.Y=421|Color=8388608|FontID=5|IsHidden=T|Text=http://www.amphenolrf.com/downloads/dl/file/id/2712/product/3102/901_143_6rfx_customer_drawing.pdf|Name=Datasheet URL|IsMirrored=T
|RECORD=41|OwnerIndex=1266|IndexInSheet=26|OwnerPartId=-1|Location.X=1007|Location.Y=421|Color=8388608|FontID=1|IsHidden=T|Text=CoaxialConnectors(RF)|Name=Family|IsMirrored=T
|RECORD=41|OwnerIndex=1266|IndexInSheet=27|OwnerPartId=-1|Location.X=1007|Location.Y=421|Color=8388608|FontID=1|IsHidden=T|Text=SMA,RFX|Name=Online Catalog|IsMirrored=T
|RECORD=41|OwnerIndex=1266|IndexInSheet=28|OwnerPartId=-1|Location.X=1007|Location.Y=421|Color=8388608|FontID=1|IsHidden=T|Text=18GHz|Name=Frequency - Max|IsMirrored=T
|RECORD=41|OwnerIndex=1266|IndexInSheet=29|OwnerPartId=-1|Location.X=1007|Location.Y=421|Color=8388608|FontID=1|IsHidden=T|Text=Solder|Name=Contact Termination|IsMirrored=T
|RECORD=41|OwnerIndex=1266|IndexInSheet=30|OwnerPartId=-1|Location.X=1007|Location.Y=421|Color=8388608|FontID=5|IsHidden=T|Text=http://www.amphenol.com/|Name=Manufacturer URL|IsMirrored=T
|RECORD=41|OwnerIndex=1266|IndexInSheet=31|OwnerPartId=-1|Location.X=1007|Location.Y=421|Color=8388608|FontID=1|IsHidden=T|Text=Amphenol|Name=Manufacturer|IsMirrored=T
|RECORD=41|OwnerIndex=1266|IndexInSheet=32|OwnerPartId=-1|Location.X=1007|Location.Y=421|Color=8388608|FontID=1|IsHidden=T|Text=-65°C~165°C|Name=Operating Temperature|IsMirrored=T
|RECORD=41|OwnerIndex=1266|IndexInSheet=33|OwnerPartId=-1|Location.X=1007|Location.Y=421|Color=8388608|FontID=1|IsHidden=T|Text=Connectors,Interconnects|Name=Category|IsMirrored=T
|RECORD=41|OwnerIndex=1266|IndexInSheet=34|OwnerPartId=-1|Location.X=1007|Location.Y=421|Color=8388608|FontID=1|IsHidden=T|Text=Bulk|Name=Packaging|IsMirrored=T
|RECORD=41|OwnerIndex=1266|IndexInSheet=35|OwnerPartId=-1|Location.X=1007|Location.Y=421|Color=8388608|FontID=1|IsHidden=T|Text=Gold|Name=Body Finish|IsMirrored=T
|RECORD=41|OwnerIndex=1266|IndexInSheet=36|OwnerPartId=-1|Location.X=1007|Location.Y=421|Color=8388608|FontID=1|IsHidden=T|Text=Polytetrafluoroethylene(PTFE)|Name=Dielectric Material|IsMirrored=T
|RECORD=41|OwnerIndex=1266|IndexInSheet=37|OwnerPartId=-1|Location.X=1007|Location.Y=421|Color=8388608|FontID=1|IsHidden=T|Text=BerylliumCopper|Name=Center Contact Material|IsMirrored=T
|RECORD=41|OwnerIndex=1266|IndexInSheet=38|OwnerPartId=-1|Location.X=1007|Location.Y=421|Color=8388608|FontID=1|IsHidden=T|Text=50Ohm|Name=Impedance|IsMirrored=T
|RECORD=41|OwnerIndex=1266|IndexInSheet=39|OwnerPartId=-1|Location.X=1007|Location.Y=421|Color=8388608|FontID=1|IsHidden=T|Text=-|Name=Features|IsMirrored=T
|RECORD=41|OwnerIndex=1266|IndexInSheet=40|OwnerPartId=-1|Location.X=1007|Location.Y=421|Color=8388608|FontID=1|IsHidden=T|Text=SMA|Name=Connector Style|IsMirrored=T
|RECORD=41|OwnerIndex=1266|IndexInSheet=41|OwnerPartId=-1|Location.X=1007|Location.Y=421|Color=8388608|FontID=1|IsHidden=T|Text=Gold|Name=Center Contact Plating|IsMirrored=T
|RECORD=41|OwnerIndex=1266|IndexInSheet=42|OwnerPartId=-1|Location.X=1007|Location.Y=421|Color=8388608|FontID=1|IsHidden=T|Text=Rev. C, 06/2010|Name=Datasheet Version|IsMirrored=T
|RECORD=41|OwnerIndex=1266|IndexInSheet=43|OwnerPartId=-1|Location.X=1007|Location.Y=421|Color=8388608|FontID=1|IsHidden=T|Text=-|Name=Ingress Protection|IsMirrored=T
|RECORD=34|OwnerIndex=1266|IndexInSheet=-1|OwnerPartId=-1|Location.X=1010|Location.Y=430|Color=8388608|FontID=1|Text=J11|Name=Designator|ReadOnlyState=1|IsMirrored=T
|RECORD=41|OwnerIndex=1266|IndexInSheet=-1|OwnerPartId=-1|Location.X=1010|Location.Y=420|Color=8388608|FontID=1|Text=901-143-6RFX|Name=Comment|IsMirrored=T
|RECORD=44|OwnerIndex=1266
|RECORD=45|OwnerIndex=1318|IndexInSheet=-1|Description=THD, 5-Leads, Body 7x7mm, Pitch 2.54mm|UseComponentLibrary=T|ModelName=AMPH-901-143-6RFX_V|ModelType=PCBLIB|IsCurrent=T|DatalinksLocked=T|DatabaseDatalinksLocked=T
|RECORD=46|OwnerIndex=1319
|RECORD=48|OwnerIndex=1319
|RECORD=41|OwnerIndex=1321|IndexInSheet=-1|OwnerPartId=-1|Color=8388608|FontID=1|Text=2D|Name=Available Preview Images
|RECORD=27|IndexInSheet=124|OwnerPartId=-1|LineWidth=1|Color=8388608|LocationCount=2|X1=1020|Y1=370|X2=1020|Y2=310
|RECORD=27|IndexInSheet=125|OwnerPartId=-1|LineWidth=1|Color=8388608|LocationCount=2|X1=1030|Y1=370|X2=1030|Y2=310
|RECORD=27|IndexInSheet=126|OwnerPartId=-1|LineWidth=1|Color=8388608|LocationCount=2|X1=1040|Y1=370|X2=1040|Y2=310
|RECORD=27|IndexInSheet=127|OwnerPartId=-1|LineWidth=1|Color=8388608|LocationCount=3|X1=1090|Y1=580|X2=1090|Y2=570|X3=1090|Y3=560
|RECORD=27|IndexInSheet=128|OwnerPartId=-1|LineWidth=1|Color=8388608|LocationCount=6|X1=1010|Y1=630|X2=1010|Y2=570|X3=1020|Y3=570|X4=1030|Y4=570|X5=1040|Y5=570|X6=1090|Y6=570
|RECORD=27|IndexInSheet=129|OwnerPartId=-1|LineWidth=1|Color=8388608|LocationCount=2|X1=1020|Y1=630|X2=1020|Y2=570
|RECORD=27|IndexInSheet=130|OwnerPartId=-1|LineWidth=1|Color=8388608|LocationCount=2|X1=1030|Y1=630|X2=1030|Y2=570
|RECORD=27|IndexInSheet=131|OwnerPartId=-1|LineWidth=1|Color=8388608|LocationCount=2|X1=1040|Y1=630|X2=1040|Y2=570
|RECORD=27|IndexInSheet=132|OwnerPartId=-1|LineWidth=1|Color=8388608|LocationCount=3|X1=1370|Y1=590|X2=1370|Y2=580|X3=1370|Y3=570
|RECORD=27|IndexInSheet=133|OwnerPartId=-1|LineWidth=1|Color=8388608|LocationCount=6|X1=1290|Y1=640|X2=1290|Y2=580|X3=1300|Y3=580|X4=1310|Y4=580|X5=1320|Y5=580|X6=1370|Y6=580
|RECORD=27|IndexInSheet=134|OwnerPartId=-1|LineWidth=1|Color=8388608|LocationCount=2|X1=1300|Y1=640|X2=1300|Y2=580
|RECORD=27|IndexInSheet=135|OwnerPartId=-1|LineWidth=1|Color=8388608|LocationCount=2|X1=1310|Y1=640|X2=1310|Y2=580
|RECORD=27|IndexInSheet=136|OwnerPartId=-1|LineWidth=1|Color=8388608|LocationCount=2|X1=1320|Y1=640|X2=1320|Y2=580
|RECORD=27|IndexInSheet=137|OwnerPartId=-1|LineWidth=1|Color=8388608|LocationCount=3|X1=1370|Y1=320|X2=1370|Y2=310|X3=1370|Y3=300
|RECORD=27|IndexInSheet=138|OwnerPartId=-1|LineWidth=1|Color=8388608|LocationCount=6|X1=1290|Y1=370|X2=1290|Y2=310|X3=1300|Y3=310|X4=1310|Y4=310|X5=1320|Y5=310|X6=1370|Y6=310
|RECORD=27|IndexInSheet=139|OwnerPartId=-1|LineWidth=1|Color=8388608|LocationCount=2|X1=1300|Y1=370|X2=1300|Y2=310
|RECORD=27|IndexInSheet=140|OwnerPartId=-1|LineWidth=1|Color=8388608|LocationCount=2|X1=1310|Y1=370|X2=1310|Y2=310
|RECORD=27|IndexInSheet=141|OwnerPartId=-1|LineWidth=1|Color=8388608|LocationCount=2|X1=1320|Y1=370|X2=1320|Y2=310
|RECORD=17|IndexInSheet=142|OwnerPartId=-1|Style=4|ShowNetName=T|Location.X=980|Location.Y=700|Orientation=3|Color=128|FontID=1|Text=GND
|RECORD=27|IndexInSheet=143|OwnerPartId=-1|LineWidth=1|Color=8388608|LocationCount=5|X1=1040|Y1=720|X2=1040|Y2=710|X3=1020|Y3=710|X4=980|Y4=710|X5=980|Y5=700
|RECORD=27|IndexInSheet=144|OwnerPartId=-1|LineWidth=1|Color=8388608|LocationCount=2|X1=1020|Y1=720|X2=1020|Y2=710
|RECORD=17|IndexInSheet=145|OwnerPartId=-1|Style=4|ShowNetName=T|Location.X=980|Location.Y=440|Orientation=3|Color=128|FontID=1|Text=GND
|RECORD=27|IndexInSheet=146|OwnerPartId=-1|LineWidth=1|Color=8388608|LocationCount=5|X1=1040|Y1=460|X2=1040|Y2=450|X3=1020|Y3=450|X4=980|Y4=450|X5=980|Y5=440
|RECORD=27|IndexInSheet=147|OwnerPartId=-1|LineWidth=1|Color=8388608|LocationCount=2|X1=1020|Y1=460|X2=1020|Y2=450
|RECORD=17|IndexInSheet=148|OwnerPartId=-1|Style=4|ShowNetName=T|Location.X=1260|Location.Y=440|Orientation=3|Color=128|FontID=1|Text=GND
|RECORD=27|IndexInSheet=149|OwnerPartId=-1|LineWidth=1|Color=8388608|LocationCount=5|X1=1320|Y1=460|X2=1320|Y2=450|X3=1300|Y3=450|X4=1260|Y4=450|X5=1260|Y5=440
|RECORD=27|IndexInSheet=150|OwnerPartId=-1|LineWidth=1|Color=8388608|LocationCount=2|X1=1300|Y1=460|X2=1300|Y2=450
|RECORD=17|IndexInSheet=151|OwnerPartId=-1|Style=4|ShowNetName=T|Location.X=1260|Location.Y=710|Orientation=3|Color=128|FontID=1|Text=GND
|RECORD=27|IndexInSheet=152|OwnerPartId=-1|LineWidth=1|Color=8388608|LocationCount=5|X1=1320|Y1=730|X2=1320|Y2=720|X3=1300|Y3=720|X4=1260|Y4=720|X5=1260|Y5=710
|RECORD=27|IndexInSheet=153|OwnerPartId=-1|LineWidth=1|Color=8388608|LocationCount=2|X1=1300|Y1=730|X2=1300|Y2=720
|RECORD=41|IndexInSheet=154|OwnerPartId=-1|Color=8388608|FontID=1|IsHidden=T|Name=ConfigurationParameters|ReadOnlyState=1
|RECORD=41|IndexInSheet=155|OwnerPartId=-1|Color=8388608|FontID=1|IsHidden=T|Name=ConfiguratorName|ReadOnlyState=1
|RECORD=41|IndexInSheet=156|OwnerPartId=-1|Color=8388608|FontID=1|IsHidden=T|Name=VersionControl_RevNumber|ReadOnlyState=1
|RECORD=41|IndexInSheet=157|OwnerPartId=-1|Color=8388608|FontID=1|IsHidden=T|Name=IsUserConfigurable|ReadOnlyState=1
|RECORD=41|IndexInSheet=158|OwnerPartId=-1|Color=8388608|FontID=1|IsHidden=T|Name=VersionControl_ProjFolderRevNumber|ReadOnlyState=1
|RECORD=41|IndexInSheet=159|OwnerPartId=-1|Color=8388608|FontID=1|IsHidden=T|Name=SPICEModelCache|ReadOnlyState=1
|RECORD=29|IndexInSheet=-1|OwnerPartId=-1|Location.X=270|Location.Y=420|Color=128
|RECORD=29|IndexInSheet=-1|OwnerPartId=-1|Location.X=580|Location.Y=420|Color=128
|RECORD=29|IndexInSheet=-1|OwnerPartId=-1|Location.X=1020|Location.Y=310|Color=128
|RECORD=29|IndexInSheet=-1|OwnerPartId=-1|Location.X=1020|Location.Y=450|Color=128
|RECORD=29|IndexInSheet=-1|OwnerPartId=-1|Location.X=1020|Location.Y=570|Color=128
|RECORD=29|IndexInSheet=-1|OwnerPartId=-1|Location.X=1020|Location.Y=710|Color=128
|RECORD=29|IndexInSheet=-1|OwnerPartId=-1|Location.X=1030|Location.Y=310|Color=128
|RECORD=29|IndexInSheet=-1|OwnerPartId=-1|Location.X=1030|Location.Y=570|Color=128
|RECORD=29|IndexInSheet=-1|OwnerPartId=-1|Location.X=1040|Location.Y=310|Color=128
|RECORD=29|IndexInSheet=-1|OwnerPartId=-1|Location.X=1040|Location.Y=570|Color=128
|RECORD=29|IndexInSheet=-1|OwnerPartId=-1|Location.X=1090|Location.Y=310|Color=128
|RECORD=29|IndexInSheet=-1|OwnerPartId=-1|Location.X=1090|Location.Y=400|Color=128
|RECORD=29|IndexInSheet=-1|OwnerPartId=-1|Location.X=1090|Location.Y=570|Color=128
|RECORD=29|IndexInSheet=-1|OwnerPartId=-1|Location.X=1090|Location.Y=660|Color=128
|RECORD=29|IndexInSheet=-1|OwnerPartId=-1|Location.X=1110|Location.Y=400|Color=128
|RECORD=29|IndexInSheet=-1|OwnerPartId=-1|Location.X=1110|Location.Y=660|Color=128
|RECORD=29|IndexInSheet=-1|OwnerPartId=-1|Location.X=1300|Location.Y=310|Color=128
|RECORD=29|IndexInSheet=-1|OwnerPartId=-1|Location.X=1300|Location.Y=450|Color=128
|RECORD=29|IndexInSheet=-1|OwnerPartId=-1|Location.X=1300|Location.Y=580|Color=128
|RECORD=29|IndexInSheet=-1|OwnerPartId=-1|Location.X=1300|Location.Y=720|Color=128
|RECORD=29|IndexInSheet=-1|OwnerPartId=-1|Location.X=1310|Location.Y=310|Color=128
|RECORD=29|IndexInSheet=-1|OwnerPartId=-1|Location.X=1310|Location.Y=580|Color=128
|RECORD=29|IndexInSheet=-1|OwnerPartId=-1|Location.X=1320|Location.Y=310|Color=128
|RECORD=29|IndexInSheet=-1|OwnerPartId=-1|Location.X=1320|Location.Y=580|Color=128
|RECORD=29|IndexInSheet=-1|OwnerPartId=-1|Location.X=1370|Location.Y=310|Color=128
|RECORD=29|IndexInSheet=-1|OwnerPartId=-1|Location.X=1370|Location.Y=400|Color=128
|RECORD=29|IndexInSheet=-1|OwnerPartId=-1|Location.X=1370|Location.Y=580|Color=128
|RECORD=29|IndexInSheet=-1|OwnerPartId=-1|Location.X=1370|Location.Y=670|Color=128
|RECORD=29|IndexInSheet=-1|OwnerPartId=-1|Location.X=1390|Location.Y=400|Color=128
|RECORD=29|IndexInSheet=-1|OwnerPartId=-1|Location.X=1390|Location.Y=670|Color=128